FILE_TYPE = MACRO_DRAWING;
SET COLOR_WIRE YELLOW;
SET COLOR_PROP ORANGE;
SET COLOR_DOT WHITE;
SET COLOR_ARC YELLOW;
SET COLOR_BODY GREEN;
SET COLOR_NOTE PURPLE;
SET PROP_DISPLAY VALUE;
SET PAGE_NUMBER P152;
FORCEADD 74LVC1G17GW..1
(-7700 7225);
FORCEPROP 1 LAST PART_NUMBER AL1G0017K01
J 0
(-7834 7459);
DISPLAY 0.723404 (-7834 7459);
PAINT GREEN (-7834 7459);
DISPLAY INVISIBLE (-7834 7459);
FORCEPROP 2 LAST PART_TYPE SMLF
J 0
(-7825 7600);
DISPLAY 0.638298 (-7825 7600);
FORCEPROP 2 LAST VALUE 74LVC1G17GW
J 0
(-7825 7550);
DISPLAY 0.638298 (-7825 7550);
FORCEPROP 1 LAST MATERIAL IC
J 0
(-7834 7379);
DISPLAY 0.723404 (-7834 7379);
PAINT GREEN (-7834 7379);
FORCEPROP 1 LAST $LOCATION U75
J 0
(-7825 7500);
DISPLAY 0.723404 (-7825 7500);
PAINT GREEN (-7825 7500);
FORCEPROP 2 LASTPIN (-7875 7225) $PN 2
J 2
(-7885 7235);
DISPLAY 0.680851 (-7885 7235);
PAINT MONO (-7885 7235);
FORCEPROP 2 LASTPIN (-7875 7125) $PN 3
J 2
(-7885 7135);
DISPLAY 0.680851 (-7885 7135);
PAINT MONO (-7885 7135);
FORCEPROP 2 LASTPIN (-7525 7125) $PN 1
J 0
(-7515 7135);
DISPLAY 0.680851 (-7515 7135);
PAINT MONO (-7515 7135);
FORCEPROP 2 LASTPIN (-7875 7325) $PN 5
J 2
(-7885 7335);
DISPLAY 0.680851 (-7885 7335);
PAINT MONO (-7885 7335);
FORCEPROP 2 LASTPIN (-7525 7225) $PN 4
J 0
(-7515 7235);
DISPLAY 0.680851 (-7515 7235);
PAINT MONO (-7515 7235);
FORCEPROP 1 LAST PIN_NAMES_ROTATE True
J 0
(-7700 7225);
DISPLAY 0.489362 (-7700 7225);
PAINT GREEN (-7700 7225);
DISPLAY INVISIBLE (-7700 7225);
FORCEPROP 1 LAST CDS_LMAN_SYM_OUTLINE -125,150,125,-150
J 0
(-7700 7225);
DISPLAY 0.468085 (-7700 7225);
PAINT GREEN (-7700 7225);
DISPLAY INVISIBLE (-7700 7225);
FORCEPROP 2 LAST CDS_LIB pure_quanta
J 0
(-7700 7225);
DISPLAY INVISIBLE (-7700 7225);
FORCEPROP 2 LAST SEC_TYPE 
J 0
(-7800 7600);
DISPLAY 1.021277 (-7800 7600);
DISPLAY INVISIBLE (-7800 7600);
FORCEPROP 1 LAST PATH I1
J 0
(-7575 7075);
DISPLAY 0.723404 (-7575 7075);
PAINT GREEN (-7575 7075);
DISPLAY INVISIBLE (-7575 7075);
FORCEPROP 2 LAST CDS_LOCATION U75
J 0
(-7800 7600);
DISPLAY 1.021277 (-7800 7600);
DISPLAY INVISIBLE (-7800 7600);
FORCEPROP 2 LAST SEC 1
J 0
(-7800 7600);
DISPLAY 0.680851 (-7800 7600);
PAINT MONO (-7800 7600);
DISPLAY INVISIBLE (-7800 7600);
FORCEADD Q_RES..1
(-6250 6775);
FORCEPROP 1 LAST PART_NUMBER CS03322FB03
J 0
(-6350 6850);
DISPLAY 0.510638 (-6350 6850);
DISPLAY INVISIBLE (-6350 6850);
FORCEPROP 1 LAST PACK_TYPE 0402LF
J 0
(-5950 6775);
DISPLAY 0.510638 (-5950 6775);
FORCEPROP 1 LAST VALUE 33.2
J 2
(-6050 6775);
DISPLAY 0.510638 (-6050 6775);
FORCEPROP 1 LAST TOLERANCE 1%
J 0
(-6025 6775);
DISPLAY 0.510638 (-6025 6775);
FORCEPROP 1 LAST WATTAGE 1/16W
J 2
(-6075 6900);
DISPLAY 0.510638 (-6075 6900);
FORCEPROP 1 LAST MATERIAL CHIP
J 0
(-6350 6900);
DISPLAY 0.510638 (-6350 6900);
FORCEPROP 1 LAST $LOCATION R1504
J 0
(-6525 6775);
DISPLAY 0.510638 (-6525 6775);
FORCEPROP 1 LASTPIN (-6350 6775) $PN 1
J 0
(-6338 6787);
DISPLAY 0.787234 (-6338 6787);
FORCEPROP 1 LASTPIN (-6150 6775) $PN 2
J 0
(-6188 6787);
DISPLAY 0.787234 (-6188 6787);
FORCEPROP 2 LAST CDS_LIB pure_quanta
J 0
(-6250 6775);
PAINT MONO (-6250 6775);
DISPLAY INVISIBLE (-6250 6775);
FORCEPROP 1 LAST PATH I10
J 0
(-6300 6925);
DISPLAY 0.978723 (-6300 6925);
PAINT WHITE (-6300 6925);
DISPLAY INVISIBLE (-6300 6925);
FORCEPROP 2 LAST CDS_LOCATION R1504
J 0
(-6300 6975);
DISPLAY 1.021277 (-6300 6975);
DISPLAY INVISIBLE (-6300 6975);
FORCEPROP 2 LAST $SEC 1
J 0
(-6300 6975);
DISPLAY 0.680851 (-6300 6975);
PAINT MONO (-6300 6975);
DISPLAY INVISIBLE (-6300 6975);
FORCEPROP 2 LAST CDS_SEC 1
J 0
(-6300 6975);
DISPLAY 1.021277 (-6300 6975);
DISPLAY INVISIBLE (-6300 6975);
FORCEADD OFFPAGE..2
(-4625 6775);
FORCEPROP 2 LAST $XR0 153 
J 0
(-4436 6775);
DISPLAY 0.638298 (-4436 6775);
PAINT MONO (-4436 6775);
FORCEPROP 2 LAST CDS_LIB standard
J 0
(-4625 6775);
PAINT MONO (-4625 6775);
DISPLAY INVISIBLE (-4625 6775);
FORCEPROP 1 LAST OFFPAGE TRUE
J 0
(-4300 6650);
DISPLAY 0.872340 (-4300 6650);
PAINT GREEN (-4300 6650);
DISPLAY INVISIBLE (-4300 6650);
FORCEPROP 1 LAST COMMENT_BODY TRUE
J 0
(-4670 6680);
DISPLAY 0.872340 (-4670 6680);
PAINT GREEN (-4670 6680);
DISPLAY INVISIBLE (-4670 6680);
FORCEPROP 2 LAST PATH I11
J 0
(-4425 6825);
DISPLAY 1.021277 (-4425 6825);
DISPLAY INVISIBLE (-4425 6825);
FORCEADD OFFPAGE..2
(-4625 6550);
FORCEPROP 2 LAST $XR0 153 
J 0
(-4436 6550);
DISPLAY 0.638298 (-4436 6550);
PAINT MONO (-4436 6550);
FORCEPROP 2 LAST CDS_LIB standard
J 0
(-4625 6550);
PAINT MONO (-4625 6550);
DISPLAY INVISIBLE (-4625 6550);
FORCEPROP 1 LAST OFFPAGE TRUE
J 0
(-4300 6425);
DISPLAY 0.872340 (-4300 6425);
PAINT GREEN (-4300 6425);
DISPLAY INVISIBLE (-4300 6425);
FORCEPROP 1 LAST COMMENT_BODY TRUE
J 0
(-4670 6455);
DISPLAY 0.872340 (-4670 6455);
PAINT GREEN (-4670 6455);
DISPLAY INVISIBLE (-4670 6455);
FORCEPROP 2 LAST PATH I12
J 0
(-4425 6600);
DISPLAY 1.021277 (-4425 6600);
DISPLAY INVISIBLE (-4425 6600);
FORCEADD Q_RES..1
(-6250 6550);
FORCEPROP 1 LAST PART_NUMBER CS03322FB03
J 0
(-6350 6625);
DISPLAY 0.510638 (-6350 6625);
DISPLAY INVISIBLE (-6350 6625);
FORCEPROP 1 LAST MATERIAL CHIP
J 0
(-6350 6675);
DISPLAY 0.510638 (-6350 6675);
FORCEPROP 1 LAST VALUE 33.2
J 2
(-6050 6550);
DISPLAY 0.510638 (-6050 6550);
FORCEPROP 1 LAST WATTAGE 1/16W
J 2
(-6075 6675);
DISPLAY 0.510638 (-6075 6675);
FORCEPROP 1 LAST PACK_TYPE 0402LF
J 0
(-5950 6550);
DISPLAY 0.510638 (-5950 6550);
FORCEPROP 1 LAST TOLERANCE 1%
J 0
(-6025 6550);
DISPLAY 0.510638 (-6025 6550);
FORCEPROP 1 LAST $LOCATION R1505
J 0
(-6525 6550);
DISPLAY 0.510638 (-6525 6550);
FORCEPROP 1 LASTPIN (-6350 6550) $PN 1
J 0
(-6338 6562);
DISPLAY 0.787234 (-6338 6562);
FORCEPROP 1 LASTPIN (-6150 6550) $PN 2
J 0
(-6188 6562);
DISPLAY 0.787234 (-6188 6562);
FORCEPROP 2 LAST CDS_LIB pure_quanta
J 0
(-6250 6550);
PAINT MONO (-6250 6550);
DISPLAY INVISIBLE (-6250 6550);
FORCEPROP 1 LAST PATH I13
J 0
(-6300 6700);
DISPLAY 0.978723 (-6300 6700);
PAINT WHITE (-6300 6700);
DISPLAY INVISIBLE (-6300 6700);
FORCEPROP 2 LAST CDS_LOCATION R1505
J 0
(-6300 6750);
DISPLAY 1.021277 (-6300 6750);
DISPLAY INVISIBLE (-6300 6750);
FORCEPROP 2 LAST $SEC 1
J 0
(-6300 6750);
DISPLAY 0.680851 (-6300 6750);
PAINT MONO (-6300 6750);
DISPLAY INVISIBLE (-6300 6750);
FORCEPROP 2 LAST CDS_SEC 1
J 0
(-6300 6750);
DISPLAY 1.021277 (-6300 6750);
DISPLAY INVISIBLE (-6300 6750);
FORCEADD UNIVERSAL_GND..1
(-7875 6975);
FORCEPROP 3 LASTPIN (-7875 7025) SIG_NAME GND\g
J 0
(-7865 7035);
DISPLAY 0.659574 (-7865 7035);
PAINT MONO (-7865 7035);
DISPLAY INVISIBLE (-7865 7035);
FORCEPROP 2 LAST CDS_LIB logical_power
J 0
(-7875 6975);
PAINT MONO (-7875 6975);
DISPLAY INVISIBLE (-7875 6975);
FORCEPROP 1 LAST HDL_POWER GND
J 1
(-7850 6900);
DISPLAY 0.872340 (-7850 6900);
PAINT GREEN (-7850 6900);
DISPLAY INVISIBLE (-7850 6900);
FORCEPROP 1 LAST PATH I14
J 0
(-7800 6975);
DISPLAY 0.872340 (-7800 6975);
PAINT AQUA (-7800 6975);
DISPLAY INVISIBLE (-7800 6975);
FORCEADD OFFPAGE..1
(-8850 7225);
FORCEPROP 2 LAST $XR0 158 
J 0
(-9102 7225);
DISPLAY 0.638298 (-9102 7225);
PAINT MONO (-9102 7225);
FORCEPROP 2 LAST CDS_LIB standard
J 0
(-8850 7225);
PAINT MONO (-8850 7225);
DISPLAY INVISIBLE (-8850 7225);
FORCEPROP 1 LAST OFFPAGE TRUE
J 0
(-8525 7100);
DISPLAY 0.872340 (-8525 7100);
PAINT GREEN (-8525 7100);
DISPLAY INVISIBLE (-8525 7100);
FORCEPROP 1 LAST COMMENT_BODY TRUE
J 0
(-8725 7125);
DISPLAY 0.872340 (-8725 7125);
PAINT GREEN (-8725 7125);
DISPLAY INVISIBLE (-8725 7125);
FORCEPROP 2 LAST PATH I2
J 0
(-8800 7300);
DISPLAY 1.021277 (-8800 7300);
DISPLAY INVISIBLE (-8800 7300);
FORCEADD OFFPAGE..1
(-10375 4150);
FORCEPROP 2 LAST $XR0 153 
J 0
(-10627 4150);
DISPLAY 0.638298 (-10627 4150);
PAINT MONO (-10627 4150);
FORCEPROP 2 LAST CDS_LIB standard
J 0
(-10375 4150);
PAINT MONO (-10375 4150);
DISPLAY INVISIBLE (-10375 4150);
FORCEPROP 1 LAST OFFPAGE TRUE
J 0
(-10050 4025);
DISPLAY 0.872340 (-10050 4025);
PAINT GREEN (-10050 4025);
DISPLAY INVISIBLE (-10050 4025);
FORCEPROP 1 LAST COMMENT_BODY TRUE
J 0
(-10250 4050);
DISPLAY 0.872340 (-10250 4050);
PAINT GREEN (-10250 4050);
DISPLAY INVISIBLE (-10250 4050);
FORCEPROP 2 LAST PATH I21
J 0
(-10650 4200);
DISPLAY 1.021277 (-10650 4200);
DISPLAY INVISIBLE (-10650 4200);
FORCEADD Q_CAP..1
(-8075 4650);
FORCEPROP 1 LAST PART_NUMBER CH4104K1B00
J 0
(-8025 4500);
DISPLAY 0.510638 (-8025 4500);
DISPLAY INVISIBLE (-8025 4500);
FORCEPROP 1 LAST VALUE 0.1UF
J 0
(-8025 4700);
DISPLAY 0.510638 (-8025 4700);
FORCEPROP 1 LAST TOLERANCE 10%
J 0
(-8025 4600);
DISPLAY 0.510638 (-8025 4600);
FORCEPROP 1 LAST MATERIAL X7R
J 0
(-8025 4550);
DISPLAY 0.510638 (-8025 4550);
FORCEPROP 1 LAST PACK_TYPE 0402
J 0
(-8025 4450);
DISPLAY 0.510638 (-8025 4450);
FORCEPROP 1 LAST VOLTAGE 25V
J 0
(-8025 4650);
DISPLAY 0.510638 (-8025 4650);
FORCEPROP 1 LAST $LOCATION C1175
J 0
(-8025 4750);
DISPLAY 0.978723 (-8025 4750);
FORCEPROP 1 LASTPIN (-8075 4750) $PN 1
J 0
(-8065 4730);
DISPLAY 0.787234 (-8065 4730);
FORCEPROP 1 LASTPIN (-8075 4550) $PN 2
J 0
(-8065 4530);
DISPLAY 0.787234 (-8065 4530);
FORCEPROP 2 LAST CDS_LIB pure_quanta
J 2
(-8075 4650);
PAINT MONO (-8075 4650);
DISPLAY INVISIBLE (-8075 4650);
FORCEPROP 1 LAST PATH I24
J 0
(-8025 4800);
DISPLAY 0.978723 (-8025 4800);
PAINT WHITE (-8025 4800);
DISPLAY INVISIBLE (-8025 4800);
FORCEPROP 2 LAST CDS_LOCATION C1175
J 0
(-8025 4850);
DISPLAY 1.021277 (-8025 4850);
DISPLAY INVISIBLE (-8025 4850);
FORCEPROP 2 LAST $SEC 1
J 0
(-8025 4850);
DISPLAY 0.680851 (-8025 4850);
PAINT MONO (-8025 4850);
DISPLAY INVISIBLE (-8025 4850);
FORCEPROP 2 LAST CDS_SEC 1
J 0
(-8025 4850);
DISPLAY 1.021277 (-8025 4850);
DISPLAY INVISIBLE (-8025 4850);
FORCEADD UNIVERSAL_GND..1
(-8075 4425);
FORCEPROP 3 LASTPIN (-8075 4475) SIG_NAME GND\g
J 0
(-8065 4485);
DISPLAY 0.659574 (-8065 4485);
PAINT MONO (-8065 4485);
DISPLAY INVISIBLE (-8065 4485);
FORCEPROP 2 LAST CDS_LIB logical_power
J 0
(-8075 4425);
PAINT MONO (-8075 4425);
DISPLAY INVISIBLE (-8075 4425);
FORCEPROP 1 LAST HDL_POWER GND
J 1
(-8050 4350);
DISPLAY 0.872340 (-8050 4350);
PAINT GREEN (-8050 4350);
DISPLAY INVISIBLE (-8050 4350);
FORCEPROP 1 LAST PATH I25
J 0
(-8000 4425);
DISPLAY 0.872340 (-8000 4425);
PAINT AQUA (-8000 4425);
DISPLAY INVISIBLE (-8000 4425);
FORCEADD Q_RES..1
(-6900 4100);
FORCEPROP 1 LAST PART_NUMBER CS03322FB03
J 0
(-7000 4175);
DISPLAY 0.510638 (-7000 4175);
DISPLAY INVISIBLE (-7000 4175);
FORCEPROP 1 LAST PACK_TYPE 0402LF
J 0
(-7025 4225);
DISPLAY 0.510638 (-7025 4225);
FORCEPROP 1 LAST VALUE 33.2
J 2
(-6700 4100);
DISPLAY 0.510638 (-6700 4100);
FORCEPROP 1 LAST TOLERANCE 1%
J 0
(-6675 4100);
DISPLAY 0.510638 (-6675 4100);
FORCEPROP 1 LAST MATERIAL CHIP
J 0
(-6575 4100);
DISPLAY 0.510638 (-6575 4100);
FORCEPROP 1 LAST WATTAGE 1/16W
J 2
(-6725 4225);
DISPLAY 0.510638 (-6725 4225);
FORCEPROP 1 LAST $LOCATION R1594
J 0
(-7150 4100);
DISPLAY 0.638298 (-7150 4100);
FORCEPROP 1 LASTPIN (-7000 4100) $PN 1
J 0
(-6988 4112);
DISPLAY 0.787234 (-6988 4112);
FORCEPROP 1 LASTPIN (-6800 4100) $PN 2
J 0
(-6838 4112);
DISPLAY 0.787234 (-6838 4112);
FORCEPROP 2 LAST CDS_LIB pure_quanta
J 0
(-6900 4100);
PAINT MONO (-6900 4100);
DISPLAY INVISIBLE (-6900 4100);
FORCEPROP 1 LAST PATH I26
J 0
(-6950 4250);
DISPLAY 0.978723 (-6950 4250);
PAINT WHITE (-6950 4250);
DISPLAY INVISIBLE (-6950 4250);
FORCEPROP 2 LAST CDS_LOCATION R1594
J 0
(-6950 4300);
DISPLAY 1.021277 (-6950 4300);
DISPLAY INVISIBLE (-6950 4300);
FORCEPROP 2 LAST $SEC 1
J 0
(-6950 4300);
DISPLAY 0.680851 (-6950 4300);
PAINT MONO (-6950 4300);
DISPLAY INVISIBLE (-6950 4300);
FORCEPROP 2 LAST CDS_SEC 1
J 0
(-6950 4300);
DISPLAY 1.021277 (-6950 4300);
DISPLAY INVISIBLE (-6950 4300);
FORCEADD OFFPAGE..1
(-8875 5675);
FORCEPROP 2 LAST $XR2 220 
J 0
(-9367 5675);
DISPLAY 0.638298 (-9367 5675);
PAINT MONO (-9367 5675);
FORCEPROP 2 LAST $XR1 161 
J 0
(-9247 5675);
DISPLAY 0.638298 (-9247 5675);
PAINT MONO (-9247 5675);
FORCEPROP 2 LAST $XR0 215 
J 0
(-9127 5675);
DISPLAY 0.638298 (-9127 5675);
PAINT MONO (-9127 5675);
FORCEPROP 2 LAST CDS_LIB standard
J 0
(-8875 5675);
PAINT MONO (-8875 5675);
DISPLAY INVISIBLE (-8875 5675);
FORCEPROP 1 LAST OFFPAGE TRUE
J 0
(-8550 5550);
DISPLAY 0.872340 (-8550 5550);
PAINT GREEN (-8550 5550);
DISPLAY INVISIBLE (-8550 5550);
FORCEPROP 1 LAST COMMENT_BODY TRUE
J 0
(-8750 5575);
DISPLAY 0.872340 (-8750 5575);
PAINT GREEN (-8750 5575);
DISPLAY INVISIBLE (-8750 5575);
FORCEPROP 2 LAST PATH I29
J 0
(-9150 5725);
DISPLAY 1.021277 (-9150 5725);
DISPLAY INVISIBLE (-9150 5725);
FORCEADD UNIVERSAL_GND..1
(-8200 7325);
FORCEPROP 3 LASTPIN (-8200 7375) SIG_NAME GND\g
J 0
(-8190 7385);
DISPLAY 0.659574 (-8190 7385);
PAINT MONO (-8190 7385);
DISPLAY INVISIBLE (-8190 7385);
FORCEPROP 2 LAST CDS_LIB logical_power
J 0
(-8200 7325);
PAINT MONO (-8200 7325);
DISPLAY INVISIBLE (-8200 7325);
FORCEPROP 1 LAST HDL_POWER GND
J 1
(-8175 7250);
DISPLAY 0.872340 (-8175 7250);
PAINT GREEN (-8175 7250);
DISPLAY INVISIBLE (-8175 7250);
FORCEPROP 1 LAST PATH I3
J 0
(-8125 7325);
DISPLAY 0.872340 (-8125 7325);
PAINT AQUA (-8125 7325);
DISPLAY INVISIBLE (-8125 7325);
FORCEADD UNIVERSAL_GND..1
(-7900 5350);
FORCEPROP 3 LASTPIN (-7900 5400) SIG_NAME GND\g
J 0
(-7890 5410);
DISPLAY 0.659574 (-7890 5410);
PAINT MONO (-7890 5410);
DISPLAY INVISIBLE (-7890 5410);
FORCEPROP 2 LAST CDS_LIB logical_power
J 0
(-7900 5350);
PAINT MONO (-7900 5350);
DISPLAY INVISIBLE (-7900 5350);
FORCEPROP 1 LAST HDL_POWER GND
J 1
(-7875 5275);
DISPLAY 0.872340 (-7875 5275);
PAINT GREEN (-7875 5275);
DISPLAY INVISIBLE (-7875 5275);
FORCEPROP 1 LAST PATH I32
J 0
(-7825 5350);
DISPLAY 0.872340 (-7825 5350);
PAINT AQUA (-7825 5350);
DISPLAY INVISIBLE (-7825 5350);
FORCEADD UNIVERSAL_POWER..1
(-8075 5000);
FORCEPROP 3 LASTPIN (-8075 4950) SIG_NAME P3V3_AUX\g
J 0
(-8065 4960);
DISPLAY 0.659574 (-8065 4960);
PAINT MONO (-8065 4960);
DISPLAY INVISIBLE (-8065 4960);
FORCEPROP 1 LAST HDL_POWER P3V3_AUX
J 1
(-8075 5050);
DISPLAY 0.872340 (-8075 5050);
PAINT GREEN (-8075 5050);
FORCEPROP 2 LAST CDS_LIB logical_power
J 0
(-8075 5000);
PAINT MONO (-8075 5000);
DISPLAY INVISIBLE (-8075 5000);
FORCEPROP 1 LAST PATH I36
J 0
(-8025 5025);
DISPLAY 0.872340 (-8025 5025);
PAINT AQUA (-8025 5025);
DISPLAY INVISIBLE (-8025 5025);
FORCEADD Q_RES..2
(-9575 4475);
FORCEPROP 1 LAST PART_NUMBER CS31002FB08
J 0
(-9535 4350);
DISPLAY 0.638298 (-9535 4350);
DISPLAY INVISIBLE (-9535 4350);
FORCEPROP 1 LAST PACK_TYPE 0402LF
J 0
(-9535 4300);
DISPLAY 0.638298 (-9535 4300);
FORCEPROP 1 LAST VALUE 10K
J 0
(-9530 4550);
DISPLAY 0.638298 (-9530 4550);
FORCEPROP 1 LAST WATTAGE 1/16W
J 0
(-9535 4450);
DISPLAY 0.638298 (-9535 4450);
FORCEPROP 1 LAST TOLERANCE 1%
J 0
(-9530 4500);
DISPLAY 0.638298 (-9530 4500);
FORCEPROP 1 LAST MATERIAL CHIP
J 0
(-9535 4400);
DISPLAY 0.638298 (-9535 4400);
FORCEPROP 1 LAST $LOCATION R1592
J 0
(-9530 4600);
DISPLAY 0.808511 (-9530 4600);
FORCEPROP 1 LASTPIN (-9575 4575) $PN 1
J 0
(-9570 4537);
DISPLAY 0.787234 (-9570 4537);
FORCEPROP 1 LASTPIN (-9575 4375) $PN 2
J 0
(-9570 4385);
DISPLAY 0.787234 (-9570 4385);
FORCEPROP 2 LAST CDS_LIB pure_quanta
J 0
(-9575 4475);
PAINT MONO (-9575 4475);
DISPLAY INVISIBLE (-9575 4475);
FORCEPROP 1 LAST PATH I37
J 0
(-9525 4650);
DISPLAY 0.978723 (-9525 4650);
PAINT WHITE (-9525 4650);
DISPLAY INVISIBLE (-9525 4650);
FORCEPROP 2 LAST CDS_LOCATION R1592
J 2
(-9525 4700);
DISPLAY 1.021277 (-9525 4700);
DISPLAY INVISIBLE (-9525 4700);
FORCEPROP 2 LAST $SEC 1
J 2
(-9525 4700);
DISPLAY 0.680851 (-9525 4700);
PAINT MONO (-9525 4700);
DISPLAY INVISIBLE (-9525 4700);
FORCEPROP 2 LAST CDS_SEC 1
J 2
(-9525 4700);
DISPLAY 1.021277 (-9525 4700);
DISPLAY INVISIBLE (-9525 4700);
FORCEADD UNIVERSAL_POWER..1
(-9575 4825);
FORCEPROP 3 LASTPIN (-9575 4775) SIG_NAME P3V3_OCP_SFF\g
J 0
(-9565 4785);
DISPLAY 0.659574 (-9565 4785);
PAINT MONO (-9565 4785);
DISPLAY INVISIBLE (-9565 4785);
FORCEPROP 1 LAST HDL_POWER P3V3_OCP_SFF
J 1
(-9575 4875);
DISPLAY 0.872340 (-9575 4875);
PAINT GREEN (-9575 4875);
FORCEPROP 2 LAST CDS_LIB logical_power
J 0
(-9575 4825);
PAINT MONO (-9575 4825);
DISPLAY INVISIBLE (-9575 4825);
FORCEPROP 1 LAST PATH I38
J 0
(-9525 4850);
DISPLAY 0.872340 (-9525 4850);
PAINT AQUA (-9525 4850);
DISPLAY INVISIBLE (-9525 4850);
FORCEADD OFFPAGE..2
(-4250 5575);
FORCEPROP 2 LAST $XR0 153 
J 0
(-4061 5575);
DISPLAY 0.638298 (-4061 5575);
PAINT MONO (-4061 5575);
FORCEPROP 2 LAST CDS_LIB standard
J 0
(-4250 5575);
PAINT MONO (-4250 5575);
DISPLAY INVISIBLE (-4250 5575);
FORCEPROP 1 LAST OFFPAGE TRUE
J 0
(-3925 5450);
DISPLAY 0.872340 (-3925 5450);
PAINT GREEN (-3925 5450);
DISPLAY INVISIBLE (-3925 5450);
FORCEPROP 1 LAST COMMENT_BODY TRUE
J 0
(-4295 5480);
DISPLAY 0.872340 (-4295 5480);
PAINT GREEN (-4295 5480);
DISPLAY INVISIBLE (-4295 5480);
FORCEPROP 2 LAST PATH I39
J 0
(-4050 5625);
DISPLAY 1.021277 (-4050 5625);
DISPLAY INVISIBLE (-4050 5625);
FORCEADD Q_CAP..1
R 2
(-8200 7550);
FORCEPROP 1 LAST PART_NUMBER CH4104K1B00
J 2
(-8250 7400);
DISPLAY 0.510638 (-8250 7400);
DISPLAY INVISIBLE (-8250 7400);
FORCEPROP 1 LAST VOLTAGE 25V
J 2
(-8250 7550);
DISPLAY 0.510638 (-8250 7550);
FORCEPROP 1 LAST PACK_TYPE 0402
J 2
(-8250 7350);
DISPLAY 0.510638 (-8250 7350);
FORCEPROP 1 LAST VALUE 0.1UF
J 2
(-8250 7600);
DISPLAY 0.510638 (-8250 7600);
FORCEPROP 1 LAST TOLERANCE 10%
J 2
(-8250 7500);
DISPLAY 0.510638 (-8250 7500);
FORCEPROP 1 LAST MATERIAL X7R
J 2
(-8250 7450);
DISPLAY 0.510638 (-8250 7450);
FORCEPROP 1 LAST $LOCATION C1173
J 2
(-8250 7650);
DISPLAY 0.978723 (-8250 7650);
FORCEPROP 1 LASTPIN (-8200 7650) $PN 1
J 2
(-8210 7630);
DISPLAY 0.787234 (-8210 7630);
FORCEPROP 1 LASTPIN (-8200 7450) $PN 2
J 2
(-8210 7430);
DISPLAY 0.787234 (-8210 7430);
FORCEPROP 2 LAST CDS_LIB pure_quanta
J 0
(-8200 7550);
PAINT MONO (-8200 7550);
DISPLAY INVISIBLE (-8200 7550);
FORCEPROP 1 LAST PATH I4
J 2
(-8250 7700);
DISPLAY 0.978723 (-8250 7700);
PAINT WHITE (-8250 7700);
DISPLAY INVISIBLE (-8250 7700);
FORCEPROP 2 LAST CDS_LOCATION C1173
J 0
(-8250 7750);
DISPLAY 1.021277 (-8250 7750);
DISPLAY INVISIBLE (-8250 7750);
FORCEPROP 2 LAST $SEC 1
J 0
(-8250 7750);
DISPLAY 0.680851 (-8250 7750);
PAINT MONO (-8250 7750);
DISPLAY INVISIBLE (-8250 7750);
FORCEPROP 2 LAST CDS_SEC 1
J 0
(-8250 7750);
DISPLAY 1.021277 (-8250 7750);
DISPLAY INVISIBLE (-8250 7750);
FORCEADD Q_RES..1
(-5500 5575);
FORCEPROP 1 LAST PART_NUMBER CS03322FB03
J 0
(-5600 5650);
DISPLAY 0.510638 (-5600 5650);
DISPLAY INVISIBLE (-5600 5650);
FORCEPROP 1 LAST TOLERANCE 1%
J 0
(-5275 5575);
DISPLAY 0.510638 (-5275 5575);
FORCEPROP 1 LAST PACK_TYPE 0402LF
J 0
(-5200 5575);
DISPLAY 0.510638 (-5200 5575);
FORCEPROP 1 LAST VALUE 33.2
J 2
(-5300 5575);
DISPLAY 0.510638 (-5300 5575);
FORCEPROP 1 LAST WATTAGE 1/16W
J 2
(-5325 5700);
DISPLAY 0.510638 (-5325 5700);
FORCEPROP 1 LAST MATERIAL CHIP
J 0
(-5600 5700);
DISPLAY 0.510638 (-5600 5700);
FORCEPROP 1 LAST $LOCATION R1595
J 0
(-5775 5575);
DISPLAY 0.638298 (-5775 5575);
FORCEPROP 1 LASTPIN (-5600 5575) $PN 1
J 0
(-5588 5587);
DISPLAY 0.787234 (-5588 5587);
FORCEPROP 1 LASTPIN (-5400 5575) $PN 2
J 0
(-5438 5587);
DISPLAY 0.787234 (-5438 5587);
FORCEPROP 2 LAST CDS_LIB pure_quanta
J 0
(-5500 5575);
PAINT MONO (-5500 5575);
DISPLAY INVISIBLE (-5500 5575);
FORCEPROP 1 LAST PATH I40
J 0
(-5550 5725);
DISPLAY 0.978723 (-5550 5725);
PAINT WHITE (-5550 5725);
DISPLAY INVISIBLE (-5550 5725);
FORCEPROP 2 LAST CDS_LOCATION R1595
J 0
(-5550 5775);
DISPLAY 1.021277 (-5550 5775);
DISPLAY INVISIBLE (-5550 5775);
FORCEPROP 2 LAST $SEC 1
J 0
(-5550 5775);
DISPLAY 0.680851 (-5550 5775);
PAINT MONO (-5550 5775);
DISPLAY INVISIBLE (-5550 5775);
FORCEPROP 2 LAST CDS_SEC 1
J 0
(-5550 5775);
DISPLAY 1.021277 (-5550 5775);
DISPLAY INVISIBLE (-5550 5775);
FORCEADD UNIVERSAL_POWER..1
(-6050 6150);
FORCEPROP 3 LASTPIN (-6050 6100) SIG_NAME P3V3_AUX\g
J 0
(-6040 6110);
DISPLAY 0.659574 (-6040 6110);
PAINT MONO (-6040 6110);
DISPLAY INVISIBLE (-6040 6110);
FORCEPROP 1 LAST HDL_POWER P3V3_AUX
J 1
(-6050 6200);
DISPLAY 0.872340 (-6050 6200);
PAINT GREEN (-6050 6200);
FORCEPROP 2 LAST CDS_LIB logical_power
J 0
(-6050 6150);
PAINT MONO (-6050 6150);
DISPLAY INVISIBLE (-6050 6150);
FORCEPROP 1 LAST PATH I41
J 0
(-6000 6175);
DISPLAY 0.872340 (-6000 6175);
PAINT AQUA (-6000 6175);
DISPLAY INVISIBLE (-6000 6175);
FORCEADD Q_RES..2
(-6050 5950);
FORCEPROP 1 LAST PART_NUMBER CS24702FB06
J 0
(-6010 5825);
DISPLAY 0.787234 (-6010 5825);
DISPLAY INVISIBLE (-6010 5825);
FORCEPROP 1 LAST MATERIAL CHIP
J 0
(-6010 5875);
DISPLAY 0.787234 (-6010 5875);
PAINT RED (-6010 5875);
FORCEPROP 1 LAST WATTAGE 1/16W
J 0
(-6010 5925);
DISPLAY 0.787234 (-6010 5925);
FORCEPROP 1 LAST TOLERANCE 1%
J 0
(-6005 5975);
DISPLAY 0.787234 (-6005 5975);
FORCEPROP 1 LAST VALUE 4.7K
J 0
(-6005 6025);
DISPLAY 0.787234 (-6005 6025);
FORCEPROP 1 LAST PACK_TYPE 0402LF
J 0
(-6010 5775);
DISPLAY 0.787234 (-6010 5775);
FORCEPROP 1 LAST $LOCATION R1593
J 0
(-6005 6075);
DISPLAY 0.787234 (-6005 6075);
FORCEPROP 1 LASTPIN (-6050 6050) $PN 1
J 0
(-6045 6012);
DISPLAY 0.787234 (-6045 6012);
FORCEPROP 1 LASTPIN (-6050 5850) $PN 2
J 0
(-6045 5860);
DISPLAY 0.787234 (-6045 5860);
FORCEPROP 1 LAST PATH I42
J 0
(-6000 6125);
DISPLAY 0.978723 (-6000 6125);
PAINT WHITE (-6000 6125);
DISPLAY INVISIBLE (-6000 6125);
FORCEPROP 2 LAST CDS_LIB pure_quanta
J 0
(-6050 5950);
PAINT MONO (-6050 5950);
DISPLAY INVISIBLE (-6050 5950);
FORCEPROP 2 LAST CDS_LOCATION R1593
J 0
(-6000 6175);
DISPLAY 1.021277 (-6000 6175);
DISPLAY INVISIBLE (-6000 6175);
FORCEPROP 2 LAST $SEC 1
J 0
(-6000 6175);
DISPLAY 0.680851 (-6000 6175);
PAINT MONO (-6000 6175);
DISPLAY INVISIBLE (-6000 6175);
FORCEPROP 2 LAST CDS_SEC 1
J 0
(-6000 6175);
DISPLAY 1.021277 (-6000 6175);
DISPLAY INVISIBLE (-6000 6175);
FORCEADD UNIVERSAL_POWER..1
(-6950 6325);
FORCEPROP 3 LASTPIN (-6950 6275) SIG_NAME P3V3_AUX\g
J 0
(-6940 6285);
DISPLAY 0.659574 (-6940 6285);
PAINT MONO (-6940 6285);
DISPLAY INVISIBLE (-6940 6285);
FORCEPROP 1 LAST HDL_POWER P3V3_AUX
J 1
(-6950 6375);
DISPLAY 0.872340 (-6950 6375);
PAINT GREEN (-6950 6375);
FORCEPROP 2 LAST CDS_LIB logical_power
J 0
(-6950 6325);
PAINT MONO (-6950 6325);
DISPLAY INVISIBLE (-6950 6325);
FORCEPROP 1 LAST PATH I43
J 0
(-6900 6350);
DISPLAY 0.872340 (-6900 6350);
PAINT AQUA (-6900 6350);
DISPLAY INVISIBLE (-6900 6350);
FORCEADD Q_CAP..1
(-6750 6050);
FORCEPROP 1 LAST PART_NUMBER CH4104K1B00
J 0
(-6700 5900);
DISPLAY 0.510638 (-6700 5900);
DISPLAY INVISIBLE (-6700 5900);
FORCEPROP 1 LAST PACK_TYPE 0402
J 0
(-6700 5850);
DISPLAY 0.510638 (-6700 5850);
FORCEPROP 1 LAST VALUE 0.1UF
J 0
(-6700 6100);
DISPLAY 0.510638 (-6700 6100);
FORCEPROP 1 LAST VOLTAGE 25V
J 0
(-6700 6050);
DISPLAY 0.510638 (-6700 6050);
FORCEPROP 1 LAST TOLERANCE 10%
J 0
(-6700 6000);
DISPLAY 0.510638 (-6700 6000);
FORCEPROP 1 LAST MATERIAL X7R
J 0
(-6700 5950);
DISPLAY 0.510638 (-6700 5950);
FORCEPROP 1 LAST $LOCATION C188
J 0
(-6700 6150);
DISPLAY 0.978723 (-6700 6150);
FORCEPROP 1 LASTPIN (-6750 6150) $PN 1
J 0
(-6740 6130);
DISPLAY 0.787234 (-6740 6130);
FORCEPROP 1 LASTPIN (-6750 5950) $PN 2
J 0
(-6740 5930);
DISPLAY 0.787234 (-6740 5930);
FORCEPROP 2 LAST CDS_LIB pure_quanta
J 2
(-6750 6050);
PAINT MONO (-6750 6050);
DISPLAY INVISIBLE (-6750 6050);
FORCEPROP 1 LAST PATH I44
J 0
(-6700 6200);
DISPLAY 0.978723 (-6700 6200);
PAINT WHITE (-6700 6200);
DISPLAY INVISIBLE (-6700 6200);
FORCEPROP 2 LAST CDS_LOCATION C188
J 0
(-6700 6250);
DISPLAY 1.021277 (-6700 6250);
DISPLAY INVISIBLE (-6700 6250);
FORCEPROP 2 LAST $SEC 1
J 0
(-6700 6250);
DISPLAY 0.680851 (-6700 6250);
PAINT MONO (-6700 6250);
DISPLAY INVISIBLE (-6700 6250);
FORCEPROP 2 LAST CDS_SEC 1
J 0
(-6700 6250);
DISPLAY 1.021277 (-6700 6250);
DISPLAY INVISIBLE (-6700 6250);
FORCEADD UNIVERSAL_GND..1
(-6750 5825);
FORCEPROP 3 LASTPIN (-6750 5875) SIG_NAME GND\g
J 0
(-6740 5885);
DISPLAY 0.659574 (-6740 5885);
PAINT MONO (-6740 5885);
DISPLAY INVISIBLE (-6740 5885);
FORCEPROP 2 LAST CDS_LIB logical_power
J 0
(-6750 5825);
PAINT MONO (-6750 5825);
DISPLAY INVISIBLE (-6750 5825);
FORCEPROP 1 LAST HDL_POWER GND
J 1
(-6725 5750);
DISPLAY 0.872340 (-6725 5750);
PAINT GREEN (-6725 5750);
DISPLAY INVISIBLE (-6725 5750);
FORCEPROP 1 LAST PATH I45
J 0
(-6675 5825);
DISPLAY 0.872340 (-6675 5825);
PAINT AQUA (-6675 5825);
DISPLAY INVISIBLE (-6675 5825);
FORCEADD PI6CV304LE..1
(-7150 2300);
FORCEPROP 1 LAST PART_NUMBER AL000304K01
J 0
(-7300 2567);
DISPLAY 0.723404 (-7300 2567);
PAINT GREEN (-7300 2567);
DISPLAY INVISIBLE (-7300 2567);
FORCEPROP 1 LAST MATERIAL IC
J 0
(-7300 2532);
DISPLAY 0.723404 (-7300 2532);
PAINT GREEN (-7300 2532);
FORCEPROP 2 LAST VALUE PI6CV304LE
J 0
(-7300 2650);
DISPLAY 1.021277 (-7300 2650);
FORCEPROP 2 LAST PART_TYPE SMLF
J 0
(-7300 2700);
DISPLAY 1.021277 (-7300 2700);
FORCEPROP 1 LAST $LOCATION U90
J 0
(-7300 2601);
DISPLAY 0.723404 (-7300 2601);
PAINT GREEN (-7300 2601);
FORCEPROP 2 LASTPIN (-7450 2375) $PN 1
J 2
(-7460 2385);
DISPLAY 0.808511 (-7460 2385);
FORCEPROP 2 LASTPIN (-6850 2125) $PN 4
J 0
(-6840 2135);
DISPLAY 0.808511 (-6840 2135);
FORCEPROP 2 LASTPIN (-7450 2225) $PN 2
J 2
(-7460 2235);
DISPLAY 0.808511 (-7460 2235);
FORCEPROP 2 LASTPIN (-6850 2475) $PN 6
J 0
(-6840 2485);
DISPLAY 0.808511 (-6840 2485);
FORCEPROP 2 LASTPIN (-6850 2375) $PN 3
J 0
(-6840 2385);
DISPLAY 0.808511 (-6840 2385);
FORCEPROP 2 LASTPIN (-6850 2325) $PN 5
J 0
(-6840 2335);
DISPLAY 0.808511 (-6840 2335);
FORCEPROP 2 LASTPIN (-6850 2275) $PN 7
J 0
(-6840 2285);
DISPLAY 0.808511 (-6840 2285);
FORCEPROP 2 LASTPIN (-6850 2225) $PN 8
J 0
(-6840 2235);
DISPLAY 0.808511 (-6840 2235);
FORCEPROP 1 LAST CDS_LMAN_SYM_OUTLINE -150,225,150,-225
J 0
(-7150 2300);
DISPLAY 0.468085 (-7150 2300);
PAINT GREEN (-7150 2300);
DISPLAY INVISIBLE (-7150 2300);
FORCEPROP 2 LAST CDS_LIB pure_quanta
J 0
(-7150 2300);
PAINT MONO (-7150 2300);
DISPLAY INVISIBLE (-7150 2300);
FORCEPROP 1 LAST PATH I46
J 0
(-7000 2035);
DISPLAY 0.723404 (-7000 2035);
PAINT GREEN (-7000 2035);
DISPLAY INVISIBLE (-7000 2035);
FORCEPROP 2 LAST CDS_LOCATION U90
J 0
(-7300 2750);
DISPLAY 1.021277 (-7300 2750);
DISPLAY INVISIBLE (-7300 2750);
FORCEPROP 2 LAST $SEC 1
J 0
(-7300 2750);
DISPLAY 0.680851 (-7300 2750);
PAINT MONO (-7300 2750);
DISPLAY INVISIBLE (-7300 2750);
FORCEPROP 2 LAST CDS_SEC 1
J 0
(-7300 2750);
DISPLAY 1.021277 (-7300 2750);
DISPLAY INVISIBLE (-7300 2750);
FORCEADD UNIVERSAL_POWER..1
(-6650 3025);
FORCEPROP 3 LASTPIN (-6650 2975) SIG_NAME P3V3_AUX\g
J 0
(-6640 2985);
DISPLAY 0.659574 (-6640 2985);
PAINT MONO (-6640 2985);
DISPLAY INVISIBLE (-6640 2985);
FORCEPROP 1 LAST HDL_POWER P3V3_AUX
J 1
(-6650 3075);
DISPLAY 0.872340 (-6650 3075);
PAINT GREEN (-6650 3075);
FORCEPROP 2 LAST CDS_LIB logical_power
J 0
(-6650 3025);
PAINT MONO (-6650 3025);
DISPLAY INVISIBLE (-6650 3025);
FORCEPROP 1 LAST PATH I47
J 0
(-6600 3050);
DISPLAY 0.872340 (-6600 3050);
PAINT AQUA (-6600 3050);
DISPLAY INVISIBLE (-6600 3050);
FORCEADD UNIVERSAL_POWER..1
(-9950 2975);
FORCEPROP 3 LASTPIN (-9950 2925) SIG_NAME P3V3_AUX\g
J 0
(-9940 2935);
DISPLAY 0.659574 (-9940 2935);
PAINT MONO (-9940 2935);
DISPLAY INVISIBLE (-9940 2935);
FORCEPROP 1 LAST HDL_POWER P3V3_AUX
J 1
(-9950 3025);
DISPLAY 0.872340 (-9950 3025);
PAINT GREEN (-9950 3025);
FORCEPROP 2 LAST CDS_LIB logical_power
J 0
(-9950 2975);
PAINT MONO (-9950 2975);
DISPLAY INVISIBLE (-9950 2975);
FORCEPROP 1 LAST PATH I48
J 0
(-9900 3000);
DISPLAY 0.872340 (-9900 3000);
PAINT AQUA (-9900 3000);
DISPLAY INVISIBLE (-9900 3000);
FORCEADD Q_CAP..1
(-6425 2700);
FORCEPROP 1 LAST PART_NUMBER CH4104K1B00
J 0
(-6375 2550);
DISPLAY 0.510638 (-6375 2550);
DISPLAY INVISIBLE (-6375 2550);
FORCEPROP 1 LAST VOLTAGE 25V
J 0
(-6375 2700);
DISPLAY 0.510638 (-6375 2700);
FORCEPROP 1 LAST MATERIAL X7R
J 0
(-6375 2600);
DISPLAY 0.510638 (-6375 2600);
FORCEPROP 1 LAST VALUE 0.1UF
J 0
(-6375 2750);
DISPLAY 0.510638 (-6375 2750);
FORCEPROP 1 LAST TOLERANCE 10%
J 0
(-6375 2650);
DISPLAY 0.510638 (-6375 2650);
FORCEPROP 1 LAST PACK_TYPE 0402
J 0
(-6375 2500);
DISPLAY 0.510638 (-6375 2500);
FORCEPROP 1 LAST $LOCATION C1275
J 0
(-6375 2800);
DISPLAY 0.978723 (-6375 2800);
FORCEPROP 1 LASTPIN (-6425 2800) $PN 1
J 0
(-6415 2780);
DISPLAY 0.787234 (-6415 2780);
FORCEPROP 1 LASTPIN (-6425 2600) $PN 2
J 0
(-6415 2580);
DISPLAY 0.787234 (-6415 2580);
FORCEPROP 2 LAST CDS_LIB pure_quanta
J 0
(-6425 2700);
PAINT MONO (-6425 2700);
DISPLAY INVISIBLE (-6425 2700);
FORCEPROP 1 LAST PATH I49
J 0
(-6375 2850);
DISPLAY 0.978723 (-6375 2850);
PAINT WHITE (-6375 2850);
DISPLAY INVISIBLE (-6375 2850);
FORCEPROP 2 LAST CDS_LOCATION C1275
J 0
(-6375 2900);
DISPLAY 1.021277 (-6375 2900);
DISPLAY INVISIBLE (-6375 2900);
FORCEPROP 2 LAST $SEC 1
J 0
(-6375 2900);
DISPLAY 0.680851 (-6375 2900);
PAINT MONO (-6375 2900);
DISPLAY INVISIBLE (-6375 2900);
FORCEPROP 2 LAST CDS_SEC 1
J 0
(-6375 2900);
DISPLAY 1.021277 (-6375 2900);
DISPLAY INVISIBLE (-6375 2900);
FORCEADD UNIVERSAL_POWER..1
(-8000 7825);
FORCEPROP 3 LASTPIN (-8000 7775) SIG_NAME P3V3_AUX\g
J 0
(-7990 7785);
DISPLAY 0.659574 (-7990 7785);
PAINT MONO (-7990 7785);
DISPLAY INVISIBLE (-7990 7785);
FORCEPROP 1 LAST HDL_POWER P3V3_AUX
J 1
(-8000 7875);
DISPLAY 0.872340 (-8000 7875);
PAINT GREEN (-8000 7875);
FORCEPROP 2 LAST CDS_LIB logical_power
J 0
(-8000 7825);
PAINT MONO (-8000 7825);
DISPLAY INVISIBLE (-8000 7825);
FORCEPROP 1 LAST PATH I5
J 0
(-7950 7850);
DISPLAY 0.872340 (-7950 7850);
PAINT AQUA (-7950 7850);
DISPLAY INVISIBLE (-7950 7850);
FORCEADD OFFPAGE..2
(-4525 2375);
FORCEPROP 2 LAST $XR0 240 
J 0
(-4336 2375);
DISPLAY 0.638298 (-4336 2375);
PAINT MONO (-4336 2375);
FORCEPROP 2 LAST CDS_LIB standard
J 0
(-4525 2375);
PAINT MONO (-4525 2375);
DISPLAY INVISIBLE (-4525 2375);
FORCEPROP 1 LAST OFFPAGE TRUE
J 0
(-4200 2250);
DISPLAY 0.872340 (-4200 2250);
PAINT GREEN (-4200 2250);
DISPLAY INVISIBLE (-4200 2250);
FORCEPROP 1 LAST COMMENT_BODY TRUE
J 0
(-4570 2280);
DISPLAY 0.872340 (-4570 2280);
PAINT GREEN (-4570 2280);
DISPLAY INVISIBLE (-4570 2280);
FORCEPROP 2 LAST PATH I50
J 0
(-4350 2450);
DISPLAY 1.021277 (-4350 2450);
DISPLAY INVISIBLE (-4350 2450);
FORCEADD OFFPAGE..2
(-4525 2325);
FORCEPROP 2 LAST $XR0 155 
J 0
(-4336 2325);
DISPLAY 0.638298 (-4336 2325);
PAINT MONO (-4336 2325);
FORCEPROP 2 LAST CDS_LIB standard
J 0
(-4525 2325);
PAINT MONO (-4525 2325);
DISPLAY INVISIBLE (-4525 2325);
FORCEPROP 1 LAST OFFPAGE TRUE
J 0
(-4200 2200);
DISPLAY 0.872340 (-4200 2200);
PAINT GREEN (-4200 2200);
DISPLAY INVISIBLE (-4200 2200);
FORCEPROP 1 LAST COMMENT_BODY TRUE
J 0
(-4570 2230);
DISPLAY 0.872340 (-4570 2230);
PAINT GREEN (-4570 2230);
DISPLAY INVISIBLE (-4570 2230);
FORCEPROP 2 LAST PATH I51
J 0
(-4350 2400);
DISPLAY 1.021277 (-4350 2400);
DISPLAY INVISIBLE (-4350 2400);
FORCEADD Q_RES..1
(-5725 2375);
FORCEPROP 1 LAST PART_NUMBER CS02742FB03
J 0
(-5800 2450);
DISPLAY 0.404255 (-5800 2450);
DISPLAY INVISIBLE (-5800 2450);
FORCEPROP 1 LAST TOLERANCE 1%
J 0
(-5475 2375);
DISPLAY 0.510638 (-5475 2375);
FORCEPROP 1 LAST VALUE 27.4
J 2
(-5500 2375);
DISPLAY 0.510638 (-5500 2375);
FORCEPROP 1 LAST PACK_TYPE 0402LF
J 0
(-5800 2475);
DISPLAY 0.404255 (-5800 2475);
FORCEPROP 1 LAST WATTAGE 1/16W
J 2
(-5550 2475);
DISPLAY 0.404255 (-5550 2475);
FORCEPROP 1 LAST MATERIAL CHIP
J 0
(-5400 2375);
DISPLAY 0.510638 (-5400 2375);
FORCEPROP 1 LAST $LOCATION R1140
J 0
(-5975 2375);
DISPLAY 0.638298 (-5975 2375);
FORCEPROP 1 LASTPIN (-5825 2375) $PN 1
J 0
(-5813 2387);
DISPLAY 0.787234 (-5813 2387);
FORCEPROP 1 LASTPIN (-5625 2375) $PN 2
J 0
(-5663 2387);
DISPLAY 0.787234 (-5663 2387);
FORCEPROP 2 LAST CDS_LIB pure_quanta
J 0
(-5725 2375);
PAINT MONO (-5725 2375);
DISPLAY INVISIBLE (-5725 2375);
FORCEPROP 1 LAST PATH I52
J 0
(-5775 2525);
DISPLAY 0.978723 (-5775 2525);
PAINT WHITE (-5775 2525);
DISPLAY INVISIBLE (-5775 2525);
FORCEPROP 2 LAST CDS_LOCATION R1140
J 0
(-5775 2575);
DISPLAY 1.021277 (-5775 2575);
DISPLAY INVISIBLE (-5775 2575);
FORCEPROP 2 LAST $SEC 1
J 0
(-5775 2575);
DISPLAY 0.680851 (-5775 2575);
PAINT MONO (-5775 2575);
DISPLAY INVISIBLE (-5775 2575);
FORCEPROP 2 LAST CDS_SEC 1
J 0
(-5775 2575);
DISPLAY 1.021277 (-5775 2575);
DISPLAY INVISIBLE (-5775 2575);
FORCEADD Q_RES..1
(-5725 2325);
FORCEPROP 1 LAST PART_NUMBER CS02742FB03
J 0
(-5800 2400);
DISPLAY 0.404255 (-5800 2400);
DISPLAY INVISIBLE (-5800 2400);
FORCEPROP 1 LAST VALUE 27.4
J 2
(-5500 2325);
DISPLAY 0.510638 (-5500 2325);
FORCEPROP 1 LAST TOLERANCE 1%
J 0
(-5475 2325);
DISPLAY 0.510638 (-5475 2325);
FORCEPROP 1 LAST MATERIAL CHIP
J 0
(-5400 2325);
DISPLAY 0.510638 (-5400 2325);
FORCEPROP 1 LAST $LOCATION R1141
J 0
(-5975 2325);
DISPLAY 0.638298 (-5975 2325);
FORCEPROP 1 LASTPIN (-5825 2325) $PN 1
J 0
(-5813 2337);
DISPLAY 0.787234 (-5813 2337);
FORCEPROP 1 LASTPIN (-5625 2325) $PN 2
J 0
(-5663 2337);
DISPLAY 0.787234 (-5663 2337);
FORCEPROP 1 LAST PACK_TYPE 0402LF
J 0
(-5400 2325);
DISPLAY 0.510638 (-5400 2325);
DISPLAY INVISIBLE (-5400 2325);
FORCEPROP 2 LAST CDS_LIB pure_quanta
J 0
(-5725 2325);
PAINT MONO (-5725 2325);
DISPLAY INVISIBLE (-5725 2325);
FORCEPROP 1 LAST WATTAGE 1/16W
J 2
(-5575 2425);
DISPLAY 0.404255 (-5575 2425);
DISPLAY INVISIBLE (-5575 2425);
FORCEPROP 1 LAST PATH I53
J 0
(-5775 2475);
DISPLAY 0.978723 (-5775 2475);
PAINT WHITE (-5775 2475);
DISPLAY INVISIBLE (-5775 2475);
FORCEPROP 2 LAST CDS_LOCATION R1141
J 0
(-5775 2525);
DISPLAY 1.021277 (-5775 2525);
DISPLAY INVISIBLE (-5775 2525);
FORCEPROP 2 LAST $SEC 1
J 0
(-5775 2525);
DISPLAY 0.680851 (-5775 2525);
PAINT MONO (-5775 2525);
DISPLAY INVISIBLE (-5775 2525);
FORCEPROP 2 LAST CDS_SEC 1
J 0
(-5775 2525);
DISPLAY 1.021277 (-5775 2525);
DISPLAY INVISIBLE (-5775 2525);
FORCEADD UNIVERSAL_GND..1
(-6425 2475);
FORCEPROP 3 LASTPIN (-6425 2525) SIG_NAME GND\g
J 0
(-6415 2535);
DISPLAY 0.659574 (-6415 2535);
PAINT MONO (-6415 2535);
DISPLAY INVISIBLE (-6415 2535);
FORCEPROP 2 LAST CDS_LIB logical_power
J 0
(-6425 2475);
PAINT MONO (-6425 2475);
DISPLAY INVISIBLE (-6425 2475);
FORCEPROP 1 LAST HDL_POWER GND
J 1
(-6400 2400);
DISPLAY 0.872340 (-6400 2400);
PAINT GREEN (-6400 2400);
DISPLAY INVISIBLE (-6400 2400);
FORCEPROP 1 LAST PATH I54
J 0
(-6350 2475);
DISPLAY 0.872340 (-6350 2475);
PAINT AQUA (-6350 2475);
DISPLAY INVISIBLE (-6350 2475);
FORCEADD UNIVERSAL_GND..1
(-6725 2000);
FORCEPROP 3 LASTPIN (-6725 2050) SIG_NAME GND\g
J 0
(-6715 2060);
DISPLAY 0.659574 (-6715 2060);
PAINT MONO (-6715 2060);
DISPLAY INVISIBLE (-6715 2060);
FORCEPROP 2 LAST CDS_LIB logical_power
J 0
(-6725 2000);
PAINT MONO (-6725 2000);
DISPLAY INVISIBLE (-6725 2000);
FORCEPROP 1 LAST HDL_POWER GND
J 1
(-6700 1925);
DISPLAY 0.872340 (-6700 1925);
PAINT GREEN (-6700 1925);
DISPLAY INVISIBLE (-6700 1925);
FORCEPROP 1 LAST PATH I55
J 0
(-6650 2000);
DISPLAY 0.872340 (-6650 2000);
PAINT AQUA (-6650 2000);
DISPLAY INVISIBLE (-6650 2000);
FORCEPROP 2 LAST ROOM IO_SLOT
J 1
(-6950 2075);
DISPLAY 0.744681 (-6950 2075);
DISPLAY INVISIBLE (-6950 2075);
FORCEADD Q_RES..1
(-8325 2375);
FORCEPROP 1 LAST PART_NUMBER CS00002JB13
J 0
(-8375 2425);
DISPLAY 0.404255 (-8375 2425);
DISPLAY INVISIBLE (-8375 2425);
FORCEPROP 1 LAST WATTAGE 1/16W
J 2
(-8150 2450);
DISPLAY 0.404255 (-8150 2450);
FORCEPROP 1 LAST PACK_TYPE 0402LF
J 0
(-8375 2475);
DISPLAY 0.404255 (-8375 2475);
FORCEPROP 1 LAST MATERIAL CHIP
J 0
(-8375 2450);
DISPLAY 0.404255 (-8375 2450);
FORCEPROP 1 LAST VALUE 0
J 2
(-8175 2375);
DISPLAY 0.510638 (-8175 2375);
FORCEPROP 1 LAST TOLERANCE 5%
J 0
(-8150 2375);
DISPLAY 0.510638 (-8150 2375);
FORCEPROP 1 LAST $LOCATION R1139
J 0
(-8575 2375);
DISPLAY 0.638298 (-8575 2375);
FORCEPROP 1 LASTPIN (-8425 2375) $PN 1
J 0
(-8413 2387);
DISPLAY 0.787234 (-8413 2387);
FORCEPROP 1 LASTPIN (-8225 2375) $PN 2
J 0
(-8263 2387);
DISPLAY 0.787234 (-8263 2387);
FORCEPROP 2 LAST CDS_LIB pure_quanta
J 0
(-8325 2375);
PAINT MONO (-8325 2375);
DISPLAY INVISIBLE (-8325 2375);
FORCEPROP 1 LAST PATH I56
J 0
(-8375 2525);
DISPLAY 0.978723 (-8375 2525);
PAINT WHITE (-8375 2525);
DISPLAY INVISIBLE (-8375 2525);
FORCEPROP 2 LAST CDS_LOCATION R1139
J 0
(-8375 2575);
DISPLAY 1.021277 (-8375 2575);
DISPLAY INVISIBLE (-8375 2575);
FORCEPROP 2 LAST $SEC 1
J 0
(-8375 2575);
DISPLAY 0.680851 (-8375 2575);
PAINT MONO (-8375 2575);
DISPLAY INVISIBLE (-8375 2575);
FORCEPROP 2 LAST CDS_SEC 1
J 0
(-8375 2575);
DISPLAY 1.021277 (-8375 2575);
DISPLAY INVISIBLE (-8375 2575);
FORCEADD UNIVERSAL_GND..1
(-9000 2100);
FORCEPROP 3 LASTPIN (-9000 2150) SIG_NAME GND\g
J 0
(-8990 2160);
DISPLAY 0.659574 (-8990 2160);
PAINT MONO (-8990 2160);
DISPLAY INVISIBLE (-8990 2160);
FORCEPROP 2 LAST CDS_LIB logical_power
J 0
(-9000 2100);
PAINT MONO (-9000 2100);
DISPLAY INVISIBLE (-9000 2100);
FORCEPROP 1 LAST HDL_POWER GND
J 1
(-8975 2025);
DISPLAY 0.872340 (-8975 2025);
PAINT GREEN (-8975 2025);
DISPLAY INVISIBLE (-8975 2025);
FORCEPROP 1 LAST PATH I57
J 0
(-8925 2100);
DISPLAY 0.872340 (-8925 2100);
PAINT AQUA (-8925 2100);
DISPLAY INVISIBLE (-8925 2100);
FORCEPROP 2 LAST ROOM IO_SLOT
J 1
(-9225 2175);
DISPLAY 0.744681 (-9225 2175);
DISPLAY INVISIBLE (-9225 2175);
FORCEADD Q_CAP..1
R 2
(-10050 2600);
FORCEPROP 1 LAST PART_NUMBER CH4104K1B00
J 2
(-10100 2450);
DISPLAY 0.510638 (-10100 2450);
DISPLAY INVISIBLE (-10100 2450);
FORCEPROP 1 LAST TOLERANCE 10%
J 2
(-10100 2550);
DISPLAY 0.510638 (-10100 2550);
FORCEPROP 1 LAST VALUE 0.1UF
J 2
(-10100 2650);
DISPLAY 0.510638 (-10100 2650);
FORCEPROP 1 LAST VOLTAGE 25V
J 2
(-10100 2600);
DISPLAY 0.510638 (-10100 2600);
FORCEPROP 1 LAST MATERIAL X7R
J 2
(-10100 2500);
DISPLAY 0.510638 (-10100 2500);
FORCEPROP 1 LAST PACK_TYPE 0402
J 2
(-10100 2400);
DISPLAY 0.510638 (-10100 2400);
FORCEPROP 1 LAST $LOCATION C1274
J 2
(-10100 2700);
DISPLAY 0.787234 (-10100 2700);
FORCEPROP 1 LASTPIN (-10050 2700) $PN 1
J 2
(-10060 2680);
DISPLAY 0.787234 (-10060 2680);
FORCEPROP 1 LASTPIN (-10050 2500) $PN 2
J 2
(-10060 2480);
DISPLAY 0.787234 (-10060 2480);
FORCEPROP 2 LAST CDS_LIB pure_quanta
J 2
(-10050 2600);
PAINT MONO (-10050 2600);
DISPLAY INVISIBLE (-10050 2600);
FORCEPROP 1 LAST PATH I59
J 2
(-10100 2750);
DISPLAY 0.978723 (-10100 2750);
PAINT WHITE (-10100 2750);
DISPLAY INVISIBLE (-10100 2750);
FORCEPROP 2 LAST CDS_LOCATION C1274
J 0
(-10100 2800);
DISPLAY 1.021277 (-10100 2800);
DISPLAY INVISIBLE (-10100 2800);
FORCEPROP 2 LAST $SEC 1
J 0
(-10100 2800);
DISPLAY 0.680851 (-10100 2800);
PAINT MONO (-10100 2800);
DISPLAY INVISIBLE (-10100 2800);
FORCEPROP 2 LAST CDS_SEC 1
J 0
(-10100 2800);
DISPLAY 1.021277 (-10100 2800);
DISPLAY INVISIBLE (-10100 2800);
FORCEADD Q_RES..1
(-6250 7225);
FORCEPROP 1 LAST PART_NUMBER CS03322FB03
J 0
(-6350 7300);
DISPLAY 0.510638 (-6350 7300);
DISPLAY INVISIBLE (-6350 7300);
FORCEPROP 1 LAST PACK_TYPE 0402LF
J 0
(-5950 7225);
DISPLAY 0.510638 (-5950 7225);
FORCEPROP 1 LAST TOLERANCE 1%
J 0
(-6025 7225);
DISPLAY 0.510638 (-6025 7225);
FORCEPROP 1 LAST VALUE 33.2
J 2
(-6050 7225);
DISPLAY 0.510638 (-6050 7225);
FORCEPROP 1 LAST MATERIAL CHIP
J 0
(-6350 7350);
DISPLAY 0.510638 (-6350 7350);
FORCEPROP 1 LAST WATTAGE 1/16W
J 2
(-6075 7350);
DISPLAY 0.510638 (-6075 7350);
FORCEPROP 1 LAST $LOCATION R419
J 0
(-6525 7225);
DISPLAY 0.510638 (-6525 7225);
FORCEPROP 1 LASTPIN (-6350 7225) $PN 1
J 0
(-6338 7237);
DISPLAY 0.787234 (-6338 7237);
FORCEPROP 1 LASTPIN (-6150 7225) $PN 2
J 0
(-6188 7237);
DISPLAY 0.787234 (-6188 7237);
FORCEPROP 2 LAST CDS_LIB pure_quanta
J 0
(-6250 7225);
PAINT MONO (-6250 7225);
DISPLAY INVISIBLE (-6250 7225);
FORCEPROP 1 LAST PATH I6
J 0
(-6300 7375);
DISPLAY 0.978723 (-6300 7375);
PAINT WHITE (-6300 7375);
DISPLAY INVISIBLE (-6300 7375);
FORCEPROP 2 LAST CDS_LOCATION R419
J 0
(-6300 7425);
DISPLAY 1.021277 (-6300 7425);
DISPLAY INVISIBLE (-6300 7425);
FORCEPROP 2 LAST $SEC 1
J 0
(-6300 7425);
DISPLAY 0.680851 (-6300 7425);
PAINT MONO (-6300 7425);
DISPLAY INVISIBLE (-6300 7425);
FORCEPROP 2 LAST CDS_SEC 1
J 0
(-6300 7425);
DISPLAY 1.021277 (-6300 7425);
DISPLAY INVISIBLE (-6300 7425);
FORCEADD UNIVERSAL_GND..1
(-10050 2375);
FORCEPROP 3 LASTPIN (-10050 2425) SIG_NAME GND\g
J 0
(-10040 2435);
DISPLAY 0.659574 (-10040 2435);
PAINT MONO (-10040 2435);
DISPLAY INVISIBLE (-10040 2435);
FORCEPROP 2 LAST CDS_LIB logical_power
J 0
(-10050 2375);
PAINT MONO (-10050 2375);
DISPLAY INVISIBLE (-10050 2375);
FORCEPROP 1 LAST HDL_POWER GND
J 1
(-10025 2300);
DISPLAY 0.872340 (-10025 2300);
PAINT GREEN (-10025 2300);
DISPLAY INVISIBLE (-10025 2300);
FORCEPROP 1 LAST PATH I60
J 0
(-9975 2375);
DISPLAY 0.872340 (-9975 2375);
PAINT AQUA (-9975 2375);
DISPLAY INVISIBLE (-9975 2375);
FORCEPROP 2 LAST ROOM IO_SLOT
J 1
(-10275 2450);
DISPLAY 0.744681 (-10275 2450);
DISPLAY INVISIBLE (-10275 2450);
FORCEADD Q_RES..2
R 2
(-10400 2575);
FORCEPROP 1 LAST PART_NUMBER CS31002FB08
J 2
(-10440 2450);
DISPLAY 0.510638 (-10440 2450);
DISPLAY INVISIBLE (-10440 2450);
FORCEPROP 1 LAST WATTAGE 1/16W
J 2
(-10440 2550);
DISPLAY 0.510638 (-10440 2550);
FORCEPROP 1 LAST TOLERANCE 1%
J 2
(-10445 2600);
DISPLAY 0.510638 (-10445 2600);
FORCEPROP 1 LAST VALUE 10K
J 2
(-10445 2650);
DISPLAY 0.510638 (-10445 2650);
FORCEPROP 1 LAST MATERIAL CHIP
J 2
(-10440 2500);
DISPLAY 0.510638 (-10440 2500);
FORCEPROP 1 LAST PACK_TYPE 0402LF
J 2
(-10440 2400);
DISPLAY 0.510638 (-10440 2400);
FORCEPROP 1 LAST $LOCATION R1138
J 2
(-10445 2700);
DISPLAY 0.787234 (-10445 2700);
FORCEPROP 1 LASTPIN (-10400 2675) $PN 1
J 2
(-10405 2637);
DISPLAY 0.787234 (-10405 2637);
FORCEPROP 1 LASTPIN (-10400 2475) $PN 2
J 2
(-10405 2485);
DISPLAY 0.787234 (-10405 2485);
FORCEPROP 2 LAST CDS_LIB pure_quanta
J 2
(-10400 2575);
PAINT MONO (-10400 2575);
DISPLAY INVISIBLE (-10400 2575);
FORCEPROP 1 LAST PATH I61
J 2
(-10450 2750);
DISPLAY 0.978723 (-10450 2750);
PAINT WHITE (-10450 2750);
DISPLAY INVISIBLE (-10450 2750);
FORCEPROP 2 LAST CDS_LOCATION R1138
J 0
(-10450 2800);
DISPLAY 1.021277 (-10450 2800);
DISPLAY INVISIBLE (-10450 2800);
FORCEPROP 2 LAST $SEC 1
J 0
(-10450 2800);
DISPLAY 0.680851 (-10450 2800);
PAINT MONO (-10450 2800);
DISPLAY INVISIBLE (-10450 2800);
FORCEPROP 2 LAST CDS_SEC 1
J 0
(-10450 2800);
DISPLAY 1.021277 (-10450 2800);
DISPLAY INVISIBLE (-10450 2800);
FORCEADD Q_RES..2
R 2
(-9850 4475);
FORCEPROP 1 LAST PART_NUMBER CS31002FB08
J 2
(-9890 4350);
DISPLAY 0.638298 (-9890 4350);
DISPLAY INVISIBLE (-9890 4350);
FORCEPROP 1 LAST PACK_TYPE 0402LF
J 2
(-9890 4300);
DISPLAY 0.638298 (-9890 4300);
FORCEPROP 1 LAST MATERIAL CHIP
J 2
(-9890 4400);
DISPLAY 0.638298 (-9890 4400);
FORCEPROP 1 LAST WATTAGE 1/16W
J 2
(-9890 4450);
DISPLAY 0.638298 (-9890 4450);
FORCEPROP 1 LAST TOLERANCE 1%
J 2
(-9895 4500);
DISPLAY 0.638298 (-9895 4500);
FORCEPROP 1 LAST VALUE 10K
J 2
(-9895 4550);
DISPLAY 0.638298 (-9895 4550);
FORCEPROP 1 LAST $LOCATION R1824
J 2
(-9895 4600);
DISPLAY 0.787234 (-9895 4600);
FORCEPROP 1 LASTPIN (-9850 4575) $PN 1
J 2
(-9855 4537);
DISPLAY 0.787234 (-9855 4537);
FORCEPROP 1 LASTPIN (-9850 4375) $PN 2
J 2
(-9855 4385);
DISPLAY 0.787234 (-9855 4385);
FORCEPROP 2 LAST CDS_LIB pure_quanta
J 2
(-9850 4475);
PAINT MONO (-9850 4475);
DISPLAY INVISIBLE (-9850 4475);
FORCEPROP 1 LAST PATH I62
J 2
(-9900 4650);
DISPLAY 0.978723 (-9900 4650);
PAINT WHITE (-9900 4650);
DISPLAY INVISIBLE (-9900 4650);
FORCEPROP 2 LAST CDS_LOCATION R1824
J 0
(-9900 4700);
DISPLAY 1.021277 (-9900 4700);
DISPLAY INVISIBLE (-9900 4700);
FORCEPROP 2 LAST $SEC 1
J 0
(-9900 4700);
DISPLAY 0.680851 (-9900 4700);
PAINT MONO (-9900 4700);
DISPLAY INVISIBLE (-9900 4700);
FORCEPROP 2 LAST CDS_SEC 1
J 0
(-9900 4700);
DISPLAY 1.021277 (-9900 4700);
DISPLAY INVISIBLE (-9900 4700);
FORCEADD 74LVC1G07GV..1
(-7425 5675);
FORCEPROP 1 LAST PART_NUMBER AL1G0007001
J 0
(-7550 5925);
DISPLAY 0.723404 (-7550 5925);
PAINT GREEN (-7550 5925);
DISPLAY INVISIBLE (-7550 5925);
FORCEPROP 2 LAST PART_TYPE SMLF
J 0
(-7550 6150);
DISPLAY 0.638298 (-7550 6150);
FORCEPROP 2 LAST VALUE 74LVC1G07GV
J 0
(-7550 6100);
DISPLAY 0.638298 (-7550 6100);
FORCEPROP 1 LAST MATERIAL IC
J 0
(-7544 5857);
DISPLAY 0.723404 (-7544 5857);
PAINT GREEN (-7544 5857);
FORCEPROP 1 LAST $LOCATION U104
J 0
(-7550 6000);
DISPLAY 0.723404 (-7550 6000);
PAINT GREEN (-7550 6000);
FORCEPROP 0 LASTPIN (-7700 5675) $PN 2
J 2
(-7710 5685);
DISPLAY 0.680851 (-7710 5685);
PAINT MONO (-7710 5685);
FORCEPROP 0 LASTPIN (-7700 5575) $PN 3
J 2
(-7710 5585);
DISPLAY 0.680851 (-7710 5585);
PAINT MONO (-7710 5585);
FORCEPROP 0 LASTPIN (-7700 5775) $PN 1
J 2
(-7710 5785);
DISPLAY 0.680851 (-7710 5785);
PAINT MONO (-7710 5785);
FORCEPROP 0 LASTPIN (-7150 5775) $PN 5
J 0
(-7140 5785);
DISPLAY 0.680851 (-7140 5785);
PAINT MONO (-7140 5785);
FORCEPROP 0 LASTPIN (-7150 5575) $PN 4
J 0
(-7140 5585);
DISPLAY 0.680851 (-7140 5585);
PAINT MONO (-7140 5585);
FORCEPROP 1 LAST CDS_LMAN_SYM_OUTLINE -125,150,125,-150
J 0
(-7425 5675);
DISPLAY 0.468085 (-7425 5675);
PAINT GREEN (-7425 5675);
DISPLAY INVISIBLE (-7425 5675);
FORCEPROP 1 LAST NEEDS_NO_SIZE TRUE
J 0
(-7425 5675);
DISPLAY 0.723404 (-7425 5675);
PAINT GREEN (-7425 5675);
DISPLAY INVISIBLE (-7425 5675);
FORCEPROP 2 LAST CDS_LIB pure_quanta
J 0
(-7425 5675);
DISPLAY INVISIBLE (-7425 5675);
FORCEPROP 1 LAST PATH I63
J 0
(-7425 5675);
DISPLAY 0.723404 (-7425 5675);
PAINT GREEN (-7425 5675);
DISPLAY INVISIBLE (-7425 5675);
FORCEPROP 0 LAST CDS_LOCATION U104
J 0
(-7550 6200);
DISPLAY 1.021277 (-7550 6200);
DISPLAY INVISIBLE (-7550 6200);
FORCEPROP 0 LAST $SEC 1
J 0
(-7550 6200);
DISPLAY 0.680851 (-7550 6200);
PAINT MONO (-7550 6200);
DISPLAY INVISIBLE (-7550 6200);
FORCEPROP 0 LAST CDS_SEC 1
J 0
(-7550 6200);
DISPLAY 1.021277 (-7550 6200);
DISPLAY INVISIBLE (-7550 6200);
FORCEADD 74LVC1G07GV..1
(-5125 4100);
FORCEPROP 1 LAST PART_NUMBER AL1G0007001
J 0
(-5250 4350);
DISPLAY 0.723404 (-5250 4350);
PAINT GREEN (-5250 4350);
DISPLAY INVISIBLE (-5250 4350);
FORCEPROP 1 LAST MATERIAL IC
J 0
(-5244 4282);
DISPLAY 0.723404 (-5244 4282);
PAINT GREEN (-5244 4282);
FORCEPROP 2 LAST PART_TYPE SMLF
J 0
(-5250 4575);
DISPLAY 0.638298 (-5250 4575);
FORCEPROP 2 LAST VALUE 74LVC1G07GV
J 0
(-5250 4525);
DISPLAY 0.638298 (-5250 4525);
FORCEPROP 1 LAST $LOCATION U157
J 0
(-5250 4425);
DISPLAY 0.723404 (-5250 4425);
PAINT GREEN (-5250 4425);
FORCEPROP 0 LASTPIN (-5400 4100) $PN 2
J 2
(-5410 4110);
DISPLAY 0.680851 (-5410 4110);
PAINT MONO (-5410 4110);
FORCEPROP 0 LASTPIN (-5400 4000) $PN 3
J 2
(-5410 4010);
DISPLAY 0.680851 (-5410 4010);
PAINT MONO (-5410 4010);
FORCEPROP 0 LASTPIN (-5400 4200) $PN 1
J 2
(-5410 4210);
DISPLAY 0.680851 (-5410 4210);
PAINT MONO (-5410 4210);
FORCEPROP 0 LASTPIN (-4850 4200) $PN 5
J 0
(-4840 4210);
DISPLAY 0.680851 (-4840 4210);
PAINT MONO (-4840 4210);
FORCEPROP 0 LASTPIN (-4850 4000) $PN 4
J 0
(-4840 4010);
DISPLAY 0.680851 (-4840 4010);
PAINT MONO (-4840 4010);
FORCEPROP 2 LAST CDS_LIB pure_quanta
J 0
(-5125 4100);
DISPLAY INVISIBLE (-5125 4100);
FORCEPROP 1 LAST CDS_LMAN_SYM_OUTLINE -125,150,125,-150
J 0
(-5125 4100);
DISPLAY 0.468085 (-5125 4100);
PAINT GREEN (-5125 4100);
DISPLAY INVISIBLE (-5125 4100);
FORCEPROP 1 LAST NEEDS_NO_SIZE TRUE
J 0
(-5125 4100);
DISPLAY 0.723404 (-5125 4100);
PAINT GREEN (-5125 4100);
DISPLAY INVISIBLE (-5125 4100);
FORCEPROP 1 LAST PATH I65
J 0
(-5125 4100);
DISPLAY 0.723404 (-5125 4100);
PAINT GREEN (-5125 4100);
DISPLAY INVISIBLE (-5125 4100);
FORCEPROP 0 LAST CDS_LOCATION U157
J 0
(-5250 4625);
DISPLAY 1.021277 (-5250 4625);
DISPLAY INVISIBLE (-5250 4625);
FORCEPROP 0 LAST $SEC 1
J 0
(-5250 4625);
DISPLAY 0.680851 (-5250 4625);
PAINT MONO (-5250 4625);
DISPLAY INVISIBLE (-5250 4625);
FORCEPROP 0 LAST CDS_SEC 1
J 0
(-5250 4625);
DISPLAY 1.021277 (-5250 4625);
DISPLAY INVISIBLE (-5250 4625);
FORCEADD UNIVERSAL_GND..1
(-5600 3775);
FORCEPROP 3 LASTPIN (-5600 3825) SIG_NAME GND\g
J 0
(-5590 3835);
DISPLAY 0.659574 (-5590 3835);
PAINT MONO (-5590 3835);
DISPLAY INVISIBLE (-5590 3835);
FORCEPROP 2 LAST CDS_LIB logical_power
J 0
(-5600 3775);
DISPLAY INVISIBLE (-5600 3775);
FORCEPROP 1 LAST HDL_POWER GND
J 1
(-5575 3700);
DISPLAY 0.872340 (-5575 3700);
PAINT GREEN (-5575 3700);
DISPLAY INVISIBLE (-5575 3700);
FORCEPROP 1 LAST PATH I66
J 0
(-5525 3775);
DISPLAY 0.872340 (-5525 3775);
PAINT AQUA (-5525 3775);
DISPLAY INVISIBLE (-5525 3775);
FORCEADD UNIVERSAL_POWER..1
(-4700 4650);
FORCEPROP 3 LASTPIN (-4700 4600) SIG_NAME P3V3_AUX\g
J 0
(-4690 4610);
DISPLAY 0.659574 (-4690 4610);
PAINT MONO (-4690 4610);
DISPLAY INVISIBLE (-4690 4610);
FORCEPROP 1 LAST HDL_POWER P3V3_AUX
J 1
(-4700 4700);
DISPLAY 0.872340 (-4700 4700);
PAINT GREEN (-4700 4700);
FORCEPROP 2 LAST CDS_LIB logical_power
J 0
(-4700 4650);
DISPLAY INVISIBLE (-4700 4650);
FORCEPROP 1 LAST PATH I67
J 0
(-4650 4675);
DISPLAY 0.872340 (-4650 4675);
PAINT AQUA (-4650 4675);
DISPLAY INVISIBLE (-4650 4675);
FORCEADD Q_CAP..1
(-4500 4375);
FORCEPROP 1 LAST PART_NUMBER CH4104K1B00
J 0
(-4450 4225);
DISPLAY 0.510638 (-4450 4225);
DISPLAY INVISIBLE (-4450 4225);
FORCEPROP 1 LAST VALUE 0.1UF
J 0
(-4450 4425);
DISPLAY 0.510638 (-4450 4425);
FORCEPROP 1 LAST VOLTAGE 25V
J 0
(-4450 4375);
DISPLAY 0.510638 (-4450 4375);
FORCEPROP 1 LAST TOLERANCE 10%
J 0
(-4450 4325);
DISPLAY 0.510638 (-4450 4325);
FORCEPROP 1 LAST MATERIAL X7R
J 0
(-4450 4275);
DISPLAY 0.510638 (-4450 4275);
FORCEPROP 1 LAST PACK_TYPE 0402
J 0
(-4450 4175);
DISPLAY 0.510638 (-4450 4175);
FORCEPROP 1 LAST $LOCATION C1663
J 0
(-4450 4475);
DISPLAY 0.978723 (-4450 4475);
FORCEPROP 1 LASTPIN (-4500 4475) $PN 1
J 0
(-4490 4455);
DISPLAY 0.787234 (-4490 4455);
PAINT MONO (-4490 4455);
FORCEPROP 1 LASTPIN (-4500 4275) $PN 2
J 0
(-4490 4255);
DISPLAY 0.787234 (-4490 4255);
PAINT MONO (-4490 4255);
FORCEPROP 2 LAST CDS_LIB pure_quanta
J 0
(-4500 4375);
DISPLAY INVISIBLE (-4500 4375);
FORCEPROP 1 LAST PATH I68
J 0
(-4450 4525);
DISPLAY 0.978723 (-4450 4525);
PAINT WHITE (-4450 4525);
DISPLAY INVISIBLE (-4450 4525);
FORCEPROP 0 LAST CDS_LOCATION C1663
J 0
(-4450 4525);
DISPLAY 1.021277 (-4450 4525);
DISPLAY INVISIBLE (-4450 4525);
FORCEPROP 0 LAST $SEC 1
J 0
(-4450 4525);
DISPLAY 0.680851 (-4450 4525);
PAINT MONO (-4450 4525);
DISPLAY INVISIBLE (-4450 4525);
FORCEPROP 0 LAST CDS_SEC 1
J 0
(-4450 4525);
DISPLAY 1.021277 (-4450 4525);
DISPLAY INVISIBLE (-4450 4525);
FORCEADD UNIVERSAL_GND..1
(-4500 4150);
FORCEPROP 3 LASTPIN (-4500 4200) SIG_NAME GND\g
J 0
(-4490 4210);
DISPLAY 0.659574 (-4490 4210);
PAINT MONO (-4490 4210);
DISPLAY INVISIBLE (-4490 4210);
FORCEPROP 2 LAST CDS_LIB logical_power
J 0
(-4500 4150);
DISPLAY INVISIBLE (-4500 4150);
FORCEPROP 1 LAST HDL_POWER GND
J 1
(-4475 4075);
DISPLAY 0.872340 (-4475 4075);
PAINT GREEN (-4475 4075);
DISPLAY INVISIBLE (-4475 4075);
FORCEPROP 1 LAST PATH I69
J 0
(-4425 4150);
DISPLAY 0.872340 (-4425 4150);
PAINT AQUA (-4425 4150);
DISPLAY INVISIBLE (-4425 4150);
FORCEADD OFFPAGE..2
(-4625 7225);
FORCEPROP 2 LAST $XR0 153 
J 0
(-4436 7225);
DISPLAY 0.638298 (-4436 7225);
PAINT MONO (-4436 7225);
FORCEPROP 2 LAST CDS_LIB standard
J 0
(-4625 7225);
PAINT MONO (-4625 7225);
DISPLAY INVISIBLE (-4625 7225);
FORCEPROP 1 LAST OFFPAGE TRUE
J 0
(-4300 7100);
DISPLAY 0.872340 (-4300 7100);
PAINT GREEN (-4300 7100);
DISPLAY INVISIBLE (-4300 7100);
FORCEPROP 1 LAST COMMENT_BODY TRUE
J 0
(-4670 7130);
DISPLAY 0.872340 (-4670 7130);
PAINT GREEN (-4670 7130);
DISPLAY INVISIBLE (-4670 7130);
FORCEPROP 2 LAST PATH I7
J 0
(-4425 7275);
DISPLAY 1.021277 (-4425 7275);
DISPLAY INVISIBLE (-4425 7275);
FORCEADD OFFPAGE..2
(-2450 4000);
FORCEPROP 2 LAST $XR2 182 
J 0
(-2021 4000);
DISPLAY 0.638298 (-2021 4000);
PAINT MONO (-2021 4000);
FORCEPROP 2 LAST $XR1 190 
J 0
(-2141 4000);
DISPLAY 0.638298 (-2141 4000);
PAINT MONO (-2141 4000);
FORCEPROP 2 LAST $XR0 161 
J 0
(-2261 4000);
DISPLAY 0.638298 (-2261 4000);
PAINT MONO (-2261 4000);
FORCEPROP 2 LAST CDS_LIB standard
J 0
(-2450 4000);
PAINT MONO (-2450 4000);
DISPLAY INVISIBLE (-2450 4000);
FORCEPROP 1 LAST OFFPAGE TRUE
J 0
(-2125 3875);
DISPLAY 0.872340 (-2125 3875);
PAINT GREEN (-2125 3875);
DISPLAY INVISIBLE (-2125 3875);
FORCEPROP 1 LAST COMMENT_BODY TRUE
J 0
(-2495 3905);
DISPLAY 0.872340 (-2495 3905);
PAINT GREEN (-2495 3905);
DISPLAY INVISIBLE (-2495 3905);
FORCEPROP 2 LAST PATH I70
J 0
(-900 4050);
DISPLAY 1.021277 (-900 4050);
DISPLAY INVISIBLE (-900 4050);
FORCEADD Q_RES..2
(-3950 4450);
FORCEPROP 1 LAST PART_NUMBER CS24702FB06
J 0
(-3910 4325);
DISPLAY 0.638298 (-3910 4325);
DISPLAY INVISIBLE (-3910 4325);
FORCEPROP 1 LAST MATERIAL EMPTY
J 0
(-3910 4375);
DISPLAY 0.638298 (-3910 4375);
PAINT RED (-3910 4375);
FORCEPROP 1 LAST PACK_TYPE 0402LF
J 0
(-3910 4275);
DISPLAY 0.638298 (-3910 4275);
FORCEPROP 1 LAST TOLERANCE 1%
J 0
(-3905 4475);
DISPLAY 0.638298 (-3905 4475);
FORCEPROP 1 LAST WATTAGE 1/16W
J 0
(-3910 4425);
DISPLAY 0.638298 (-3910 4425);
FORCEPROP 1 LAST VALUE 4.7K
J 0
(-3905 4525);
DISPLAY 0.638298 (-3905 4525);
FORCEPROP 1 LAST $LOCATION R2487
J 0
(-3905 4575);
DISPLAY 0.978723 (-3905 4575);
FORCEPROP 1 LASTPIN (-3950 4550) $PN 1
J 0
(-3945 4512);
DISPLAY 0.787234 (-3945 4512);
PAINT MONO (-3945 4512);
FORCEPROP 1 LASTPIN (-3950 4350) $PN 2
J 0
(-3945 4360);
DISPLAY 0.787234 (-3945 4360);
PAINT MONO (-3945 4360);
FORCEPROP 2 LAST CDS_LIB pure_quanta
J 0
(-3950 4450);
DISPLAY INVISIBLE (-3950 4450);
FORCEPROP 1 LAST PATH I71
J 0
(-3900 4625);
DISPLAY 0.978723 (-3900 4625);
PAINT WHITE (-3900 4625);
DISPLAY INVISIBLE (-3900 4625);
FORCEPROP 0 LAST CDS_LOCATION R2487
J 0
(-3900 4625);
DISPLAY 1.021277 (-3900 4625);
DISPLAY INVISIBLE (-3900 4625);
FORCEPROP 0 LAST $SEC 1
J 0
(-3900 4625);
DISPLAY 0.680851 (-3900 4625);
PAINT MONO (-3900 4625);
DISPLAY INVISIBLE (-3900 4625);
FORCEPROP 0 LAST CDS_SEC 1
J 0
(-3900 4625);
DISPLAY 1.021277 (-3900 4625);
DISPLAY INVISIBLE (-3900 4625);
FORCEADD UNIVERSAL_POWER..1
(-3950 4650);
FORCEPROP 3 LASTPIN (-3950 4600) SIG_NAME P3V3_AUX\g
J 0
(-3940 4610);
DISPLAY 0.659574 (-3940 4610);
PAINT MONO (-3940 4610);
DISPLAY INVISIBLE (-3940 4610);
FORCEPROP 1 LAST HDL_POWER P3V3_AUX
J 1
(-3950 4700);
DISPLAY 0.872340 (-3950 4700);
PAINT GREEN (-3950 4700);
FORCEPROP 2 LAST CDS_LIB logical_power
J 0
(-3950 4650);
DISPLAY INVISIBLE (-3950 4650);
FORCEPROP 1 LAST PATH I72
J 0
(-3900 4675);
DISPLAY 0.872340 (-3900 4675);
PAINT AQUA (-3900 4675);
DISPLAY INVISIBLE (-3900 4675);
FORCEADD UNIVERSAL_POWER..1
(-7225 4750);
FORCEPROP 3 LASTPIN (-7225 4700) SIG_NAME P3V3_AUX\g
J 0
(-7215 4710);
DISPLAY 0.659574 (-7215 4710);
PAINT MONO (-7215 4710);
DISPLAY INVISIBLE (-7215 4710);
FORCEPROP 1 LAST HDL_POWER P3V3_AUX
J 1
(-7225 4800);
DISPLAY 0.872340 (-7225 4800);
PAINT GREEN (-7225 4800);
FORCEPROP 2 LAST CDS_LIB logical_power
J 0
(-7225 4750);
DISPLAY INVISIBLE (-7225 4750);
FORCEPROP 1 LAST PATH I73
J 0
(-7175 4775);
DISPLAY 0.872340 (-7175 4775);
PAINT AQUA (-7175 4775);
DISPLAY INVISIBLE (-7175 4775);
FORCEADD Q_RES..2
(-7225 4550);
FORCEPROP 1 LAST PART_NUMBER CS24702FB06
J 0
(-7185 4425);
DISPLAY 0.787234 (-7185 4425);
DISPLAY INVISIBLE (-7185 4425);
FORCEPROP 1 LAST MATERIAL CHIP
J 0
(-7185 4475);
DISPLAY 0.787234 (-7185 4475);
FORCEPROP 1 LAST TOLERANCE 1%
J 0
(-7180 4575);
DISPLAY 0.787234 (-7180 4575);
FORCEPROP 1 LAST PACK_TYPE 0402LF
J 0
(-7185 4375);
DISPLAY 0.787234 (-7185 4375);
FORCEPROP 1 LAST WATTAGE 1/16W
J 0
(-7185 4525);
DISPLAY 0.787234 (-7185 4525);
FORCEPROP 1 LAST VALUE 4.7K
J 0
(-7180 4625);
DISPLAY 0.787234 (-7180 4625);
FORCEPROP 1 LAST $LOCATION R2488
J 0
(-7180 4675);
DISPLAY 0.978723 (-7180 4675);
FORCEPROP 1 LASTPIN (-7225 4650) $PN 1
J 0
(-7220 4612);
DISPLAY 0.787234 (-7220 4612);
PAINT MONO (-7220 4612);
FORCEPROP 1 LASTPIN (-7225 4450) $PN 2
J 0
(-7220 4460);
DISPLAY 0.787234 (-7220 4460);
PAINT MONO (-7220 4460);
FORCEPROP 2 LAST CDS_LIB pure_quanta
J 0
(-7225 4550);
DISPLAY INVISIBLE (-7225 4550);
FORCEPROP 1 LAST PATH I74
J 0
(-7175 4725);
DISPLAY 0.978723 (-7175 4725);
PAINT WHITE (-7175 4725);
DISPLAY INVISIBLE (-7175 4725);
FORCEPROP 0 LAST CDS_LOCATION R2488
J 0
(-7175 4725);
DISPLAY 1.021277 (-7175 4725);
DISPLAY INVISIBLE (-7175 4725);
FORCEPROP 0 LAST $SEC 1
J 0
(-7175 4725);
DISPLAY 0.680851 (-7175 4725);
PAINT MONO (-7175 4725);
DISPLAY INVISIBLE (-7175 4725);
FORCEPROP 0 LAST CDS_SEC 1
J 0
(-7175 4725);
DISPLAY 1.021277 (-7175 4725);
DISPLAY INVISIBLE (-7175 4725);
FORCEADD Q_RES..1
(-3650 4000);
FORCEPROP 1 LAST PART_NUMBER CS03322FB03
J 0
(-3750 4075);
DISPLAY 0.510638 (-3750 4075);
DISPLAY INVISIBLE (-3750 4075);
FORCEPROP 1 LAST WATTAGE 1/16W
J 2
(-3475 4125);
DISPLAY 0.510638 (-3475 4125);
FORCEPROP 1 LAST VALUE 33.2
J 2
(-3450 4000);
DISPLAY 0.510638 (-3450 4000);
FORCEPROP 1 LAST TOLERANCE 1%
J 0
(-3425 4000);
DISPLAY 0.510638 (-3425 4000);
FORCEPROP 1 LAST PACK_TYPE 0402LF
J 0
(-3775 4125);
DISPLAY 0.510638 (-3775 4125);
FORCEPROP 1 LAST MATERIAL CHIP
J 0
(-3350 4000);
DISPLAY 0.510638 (-3350 4000);
FORCEPROP 1 LAST $LOCATION R2489
J 0
(-3900 4000);
DISPLAY 0.638298 (-3900 4000);
FORCEPROP 1 LASTPIN (-3750 4000) $PN 1
J 0
(-3738 4012);
DISPLAY 0.787234 (-3738 4012);
PAINT MONO (-3738 4012);
FORCEPROP 1 LASTPIN (-3550 4000) $PN 2
J 0
(-3588 4012);
DISPLAY 0.787234 (-3588 4012);
PAINT MONO (-3588 4012);
FORCEPROP 2 LAST CDS_LIB pure_quanta
J 0
(-3650 4000);
DISPLAY INVISIBLE (-3650 4000);
FORCEPROP 1 LAST PATH I75
J 0
(-3700 4150);
DISPLAY 0.978723 (-3700 4150);
PAINT WHITE (-3700 4150);
DISPLAY INVISIBLE (-3700 4150);
FORCEPROP 0 LAST CDS_LOCATION R2489
J 0
(-3475 4150);
DISPLAY 1.021277 (-3475 4150);
DISPLAY INVISIBLE (-3475 4150);
FORCEPROP 0 LAST $SEC 1
J 0
(-3475 4150);
DISPLAY 0.680851 (-3475 4150);
PAINT MONO (-3475 4150);
DISPLAY INVISIBLE (-3475 4150);
FORCEPROP 0 LAST CDS_SEC 1
J 0
(-3475 4150);
DISPLAY 1.021277 (-3475 4150);
DISPLAY INVISIBLE (-3475 4150);
FORCEADD Q_OSC4P..1
(-9450 2300);
FORCEPROP 1 LAST PART_NUMBER BF650000032
J 0
(-9625 2480);
DISPLAY 0.723404 (-9625 2480);
PAINT GREEN (-9625 2480);
DISPLAY INVISIBLE (-9625 2480);
FORCEPROP 1 LAST MATERIAL OSC
J 0
(-9625 2435);
DISPLAY 0.723404 (-9625 2435);
PAINT GREEN (-9625 2435);
FORCEPROP 2 LAST PACK_TYPE SMLF
J 0
(-9625 2575);
DISPLAY 1.021277 (-9625 2575);
FORCEPROP 2 LAST VALUE 50MHZ
J 0
(-9625 2625);
DISPLAY 1.021277 (-9625 2625);
FORCEPROP 1 LAST LOCATION OSC1
J 0
(-9625 2530);
DISPLAY 0.723404 (-9625 2530);
PAINT GREEN (-9625 2530);
FORCEPROP 0 LASTPIN (-9125 2225) $PN 2
J 0
(-9115 2235);
DISPLAY 0.680851 (-9115 2235);
PAINT MONO (-9115 2235);
FORCEPROP 0 LASTPIN (-9775 2225) $PN 1
J 2
(-9785 2235);
DISPLAY 0.680851 (-9785 2235);
PAINT MONO (-9785 2235);
FORCEPROP 0 LASTPIN (-9125 2375) $PN 3
J 0
(-9115 2385);
DISPLAY 0.680851 (-9115 2385);
PAINT MONO (-9115 2385);
FORCEPROP 0 LASTPIN (-9775 2375) $PN 4
J 2
(-9785 2385);
DISPLAY 0.680851 (-9785 2385);
PAINT MONO (-9785 2385);
FORCEPROP 1 LAST NEEDS_NO_SIZE TRUE
J 0
(-9450 2300);
DISPLAY 0.468085 (-9450 2300);
PAINT GREEN (-9450 2300);
DISPLAY INVISIBLE (-9450 2300);
FORCEPROP 2 LAST CDS_LIB pure_quanta
J 0
(-9450 2300);
DISPLAY INVISIBLE (-9450 2300);
FORCEPROP 1 LAST PATH I76
J 0
(-9300 2435);
DISPLAY 0.723404 (-9300 2435);
PAINT GREEN (-9300 2435);
DISPLAY INVISIBLE (-9300 2435);
FORCEPROP 0 LAST $SEC 1
J 0
(-9625 2675);
DISPLAY 0.680851 (-9625 2675);
PAINT MONO (-9625 2675);
DISPLAY INVISIBLE (-9625 2675);
FORCEPROP 0 LAST CDS_SEC 1
J 0
(-9625 2675);
DISPLAY 1.021277 (-9625 2675);
DISPLAY INVISIBLE (-9625 2675);
FORCEADD OFFPAGE..2
(-4525 2275);
FORCEPROP 2 LAST $XR0 161 
J 0
(-4336 2275);
DISPLAY 0.638298 (-4336 2275);
PAINT MONO (-4336 2275);
FORCEPROP 2 LAST CDS_LIB standard
J 0
(-4525 2275);
PAINT MONO (-4525 2275);
DISPLAY INVISIBLE (-4525 2275);
FORCEPROP 1 LAST OFFPAGE TRUE
J 0
(-4200 2150);
DISPLAY 0.872340 (-4200 2150);
PAINT GREEN (-4200 2150);
DISPLAY INVISIBLE (-4200 2150);
FORCEPROP 1 LAST COMMENT_BODY TRUE
J 0
(-4570 2180);
DISPLAY 0.872340 (-4570 2180);
PAINT GREEN (-4570 2180);
DISPLAY INVISIBLE (-4570 2180);
FORCEPROP 2 LAST PATH I77
J 0
(-4325 2325);
DISPLAY 1.021277 (-4325 2325);
DISPLAY INVISIBLE (-4325 2325);
FORCEADD Q_RES..1
(-5725 2275);
FORCEPROP 1 LAST PART_NUMBER CS02742FB03
J 0
(-5800 2350);
DISPLAY 0.404255 (-5800 2350);
DISPLAY INVISIBLE (-5800 2350);
FORCEPROP 1 LAST MATERIAL CHIP
J 0
(-5400 2275);
DISPLAY 0.510638 (-5400 2275);
FORCEPROP 1 LAST VALUE 27.4
J 2
(-5500 2275);
DISPLAY 0.510638 (-5500 2275);
FORCEPROP 1 LAST TOLERANCE 1%
J 0
(-5475 2275);
DISPLAY 0.510638 (-5475 2275);
FORCEPROP 1 LAST $LOCATION R3181
J 0
(-5975 2275);
DISPLAY 0.638298 (-5975 2275);
FORCEPROP 1 LASTPIN (-5825 2275) $PN 1
J 0
(-5813 2287);
DISPLAY 0.787234 (-5813 2287);
FORCEPROP 1 LASTPIN (-5625 2275) $PN 2
J 0
(-5663 2287);
DISPLAY 0.787234 (-5663 2287);
FORCEPROP 1 LAST WATTAGE 1/16W
J 2
(-5575 2375);
DISPLAY 0.404255 (-5575 2375);
DISPLAY INVISIBLE (-5575 2375);
FORCEPROP 2 LAST CDS_LIB pure_quanta
J 0
(-5725 2275);
PAINT MONO (-5725 2275);
DISPLAY INVISIBLE (-5725 2275);
FORCEPROP 1 LAST PACK_TYPE 0402LF
J 0
(-5400 2275);
DISPLAY 0.510638 (-5400 2275);
DISPLAY INVISIBLE (-5400 2275);
FORCEPROP 1 LAST PATH I78
J 0
(-5775 2425);
DISPLAY 0.978723 (-5775 2425);
PAINT WHITE (-5775 2425);
DISPLAY INVISIBLE (-5775 2425);
FORCEPROP 2 LAST CDS_LOCATION R3181
J 0
(-5775 2475);
DISPLAY 1.021277 (-5775 2475);
DISPLAY INVISIBLE (-5775 2475);
FORCEPROP 2 LAST $SEC 1
J 0
(-5775 2475);
DISPLAY 0.680851 (-5775 2475);
PAINT MONO (-5775 2475);
DISPLAY INVISIBLE (-5775 2475);
FORCEPROP 2 LAST CDS_SEC 1
J 0
(-5775 2475);
DISPLAY 1.021277 (-5775 2475);
DISPLAY INVISIBLE (-5775 2475);
FORCEADD 74LVC1G126SE7..1
(-8350 4100);
FORCEPROP 1 LAST PART_NUMBER AL1G0126009
J 0
(-8269 3809);
DISPLAY 0.723404 (-8269 3809);
PAINT GREEN (-8269 3809);
DISPLAY INVISIBLE (-8269 3809);
FORCEPROP 1 LAST MATERIAL IC
J 0
(-8244 3657);
DISPLAY 0.723404 (-8244 3657);
PAINT GREEN (-8244 3657);
FORCEPROP 2 LAST PART_TYPE SMLF
J 0
(-8225 4275);
DISPLAY 0.638298 (-8225 4275);
FORCEPROP 2 LAST VALUE 74LVC1G126SE-7
J 0
(-8325 4250);
DISPLAY 0.638298 (-8325 4250);
FORCEPROP 1 LAST LOCATION U82
J 0
(-8244 3931);
DISPLAY 0.723404 (-8244 3931);
PAINT GREEN (-8244 3931);
FORCEPROP 0 LASTPIN (-8600 4150) $PN 2
J 2
(-8610 4160);
DISPLAY 0.680851 (-8610 4160);
PAINT MONO (-8610 4160);
FORCEPROP 0 LASTPIN (-8350 3850) $PN 3
R 1
J 2
(-8360 3840);
DISPLAY 0.680851 (-8360 3840);
PAINT MONO (-8360 3840);
FORCEPROP 0 LASTPIN (-8600 4050) $PN 1
J 2
(-8610 4060);
DISPLAY 0.680851 (-8610 4060);
PAINT MONO (-8610 4060);
FORCEPROP 0 LASTPIN (-8350 4350) $PN 5
R 1
J 0
(-8360 4360);
DISPLAY 0.680851 (-8360 4360);
PAINT MONO (-8360 4360);
FORCEPROP 0 LASTPIN (-8100 4100) $PN 4
J 0
(-8090 4110);
DISPLAY 0.680851 (-8090 4110);
PAINT MONO (-8090 4110);
FORCEPROP 2 LAST CDS_LIB pure_quanta
J 0
(-8350 4100);
DISPLAY INVISIBLE (-8350 4100);
FORCEPROP 1 LAST CDS_LMAN_SYM_OUTLINE -100,100,100,-100
J 0
(-8350 4100);
DISPLAY 0.468085 (-8350 4100);
PAINT GREEN (-8350 4100);
DISPLAY INVISIBLE (-8350 4100);
FORCEPROP 1 LAST NEEDS_NO_SIZE TRUE
J 0
(-8350 4100);
DISPLAY 0.723404 (-8350 4100);
PAINT GREEN (-8350 4100);
DISPLAY INVISIBLE (-8350 4100);
FORCEPROP 1 LAST PATH I79
J 0
(-8350 4100);
DISPLAY 0.723404 (-8350 4100);
PAINT GREEN (-8350 4100);
DISPLAY INVISIBLE (-8350 4100);
FORCEPROP 0 LAST $SEC 1
J 0
(-8225 4325);
DISPLAY 0.680851 (-8225 4325);
PAINT MONO (-8225 4325);
DISPLAY INVISIBLE (-8225 4325);
FORCEPROP 0 LAST CDS_SEC 1
J 0
(-8225 4325);
DISPLAY 1.021277 (-8225 4325);
DISPLAY INVISIBLE (-8225 4325);
FORCEADD Q_RES..1
(-6250 7000);
FORCEPROP 1 LAST PART_NUMBER CS03322FB03
J 0
(-6350 7075);
DISPLAY 0.510638 (-6350 7075);
DISPLAY INVISIBLE (-6350 7075);
FORCEPROP 1 LAST VALUE 33.2
J 2
(-6050 7000);
DISPLAY 0.510638 (-6050 7000);
FORCEPROP 1 LAST TOLERANCE 1%
J 0
(-6025 7000);
DISPLAY 0.510638 (-6025 7000);
FORCEPROP 1 LAST PACK_TYPE 0402LF
J 0
(-5950 7000);
DISPLAY 0.510638 (-5950 7000);
FORCEPROP 1 LAST WATTAGE 1/16W
J 2
(-6075 7125);
DISPLAY 0.510638 (-6075 7125);
FORCEPROP 1 LAST MATERIAL CHIP
J 0
(-6350 7125);
DISPLAY 0.510638 (-6350 7125);
FORCEPROP 1 LAST $LOCATION R435
J 0
(-6525 7000);
DISPLAY 0.510638 (-6525 7000);
FORCEPROP 1 LASTPIN (-6350 7000) $PN 1
J 0
(-6338 7012);
DISPLAY 0.787234 (-6338 7012);
FORCEPROP 1 LASTPIN (-6150 7000) $PN 2
J 0
(-6188 7012);
DISPLAY 0.787234 (-6188 7012);
FORCEPROP 2 LAST CDS_LIB pure_quanta
J 0
(-6250 7000);
PAINT MONO (-6250 7000);
DISPLAY INVISIBLE (-6250 7000);
FORCEPROP 1 LAST PATH I8
J 0
(-6300 7150);
DISPLAY 0.978723 (-6300 7150);
PAINT WHITE (-6300 7150);
DISPLAY INVISIBLE (-6300 7150);
FORCEPROP 2 LAST CDS_LOCATION R435
J 0
(-6300 7200);
DISPLAY 1.021277 (-6300 7200);
DISPLAY INVISIBLE (-6300 7200);
FORCEPROP 2 LAST $SEC 1
J 0
(-6300 7200);
DISPLAY 0.680851 (-6300 7200);
PAINT MONO (-6300 7200);
DISPLAY INVISIBLE (-6300 7200);
FORCEPROP 2 LAST CDS_SEC 1
J 0
(-6300 7200);
DISPLAY 1.021277 (-6300 7200);
DISPLAY INVISIBLE (-6300 7200);
FORCEADD UNIVERSAL_GND..1
(-8350 3650);
FORCEPROP 3 LASTPIN (-8350 3700) SIG_NAME GND\g
J 0
(-8340 3710);
DISPLAY 0.659574 (-8340 3710);
PAINT MONO (-8340 3710);
DISPLAY INVISIBLE (-8340 3710);
FORCEPROP 2 LAST CDS_LIB logical_power
J 0
(-8350 3650);
PAINT MONO (-8350 3650);
DISPLAY INVISIBLE (-8350 3650);
FORCEPROP 1 LAST HDL_POWER GND
J 1
(-8325 3575);
DISPLAY 0.872340 (-8325 3575);
PAINT GREEN (-8325 3575);
DISPLAY INVISIBLE (-8325 3575);
FORCEPROP 1 LAST PATH I80
J 0
(-8275 3650);
DISPLAY 0.872340 (-8275 3650);
PAINT AQUA (-8275 3650);
DISPLAY INVISIBLE (-8275 3650);
FORCEADD OFFPAGE..1
(-4750 3225);
FORCEPROP 2 LAST $XR0 155 
J 0
(-5002 3225);
DISPLAY 0.638298 (-5002 3225);
PAINT MONO (-5002 3225);
FORCEPROP 2 LAST CDS_LIB standard
J 0
(-4750 3225);
DISPLAY INVISIBLE (-4750 3225);
FORCEPROP 1 LAST OFFPAGE TRUE
J 0
(-4425 3100);
DISPLAY 0.872340 (-4425 3100);
PAINT GREEN (-4425 3100);
DISPLAY INVISIBLE (-4425 3100);
FORCEPROP 1 LAST COMMENT_BODY TRUE
J 0
(-4625 3125);
DISPLAY 0.872340 (-4625 3125);
PAINT GREEN (-4625 3125);
DISPLAY INVISIBLE (-4625 3125);
FORCEPROP 2 LAST PATH I83
J 0
(-4700 3300);
DISPLAY 1.021277 (-4700 3300);
DISPLAY INVISIBLE (-4700 3300);
FORCEADD UNIVERSAL_GND..1
(-3775 2875);
FORCEPROP 3 LASTPIN (-3775 2925) SIG_NAME GND\g
J 0
(-3765 2935);
DISPLAY 0.659574 (-3765 2935);
PAINT MONO (-3765 2935);
DISPLAY INVISIBLE (-3765 2935);
FORCEPROP 2 LAST CDS_LIB logical_power
J 0
(-3775 2875);
DISPLAY INVISIBLE (-3775 2875);
FORCEPROP 1 LAST HDL_POWER GND
J 1
(-3750 2800);
DISPLAY 0.872340 (-3750 2800);
PAINT GREEN (-3750 2800);
DISPLAY INVISIBLE (-3750 2800);
FORCEPROP 1 LAST PATH I84
J 0
(-3700 2875);
DISPLAY 0.872340 (-3700 2875);
PAINT AQUA (-3700 2875);
DISPLAY INVISIBLE (-3700 2875);
FORCEADD UNIVERSAL_POWER..1
(-2900 3675);
FORCEPROP 3 LASTPIN (-2900 3625) SIG_NAME P3V3_AUX\g
J 0
(-2890 3635);
DISPLAY 0.659574 (-2890 3635);
PAINT MONO (-2890 3635);
DISPLAY INVISIBLE (-2890 3635);
FORCEPROP 1 LAST HDL_POWER P3V3_AUX
J 1
(-2900 3725);
DISPLAY 0.872340 (-2900 3725);
PAINT GREEN (-2900 3725);
FORCEPROP 2 LAST CDS_LIB logical_power
J 0
(-2900 3675);
DISPLAY INVISIBLE (-2900 3675);
FORCEPROP 1 LAST PATH I85
J 0
(-2850 3700);
DISPLAY 0.872340 (-2850 3700);
PAINT AQUA (-2850 3700);
DISPLAY INVISIBLE (-2850 3700);
FORCEADD UNIVERSAL_GND..1
(-2700 3175);
FORCEPROP 3 LASTPIN (-2700 3225) SIG_NAME GND\g
J 0
(-2690 3235);
DISPLAY 0.659574 (-2690 3235);
PAINT MONO (-2690 3235);
DISPLAY INVISIBLE (-2690 3235);
FORCEPROP 2 LAST CDS_LIB logical_power
J 0
(-2700 3175);
DISPLAY INVISIBLE (-2700 3175);
FORCEPROP 1 LAST HDL_POWER GND
J 1
(-2675 3100);
DISPLAY 0.872340 (-2675 3100);
PAINT GREEN (-2675 3100);
DISPLAY INVISIBLE (-2675 3100);
FORCEPROP 1 LAST PATH I86
J 0
(-2625 3175);
DISPLAY 0.872340 (-2625 3175);
PAINT AQUA (-2625 3175);
DISPLAY INVISIBLE (-2625 3175);
FORCEADD Q_CAP..1
(-2700 3400);
FORCEPROP 1 LAST PART_NUMBER CH4104K1B00
J 0
(-2650 3250);
DISPLAY 0.510638 (-2650 3250);
DISPLAY INVISIBLE (-2650 3250);
FORCEPROP 1 LAST VOLTAGE 25V
J 0
(-2650 3400);
DISPLAY 0.510638 (-2650 3400);
FORCEPROP 1 LAST VALUE 0.1UF
J 0
(-2650 3450);
DISPLAY 0.510638 (-2650 3450);
FORCEPROP 1 LAST TOLERANCE 10%
J 0
(-2650 3350);
DISPLAY 0.510638 (-2650 3350);
FORCEPROP 1 LAST MATERIAL X7R
J 0
(-2650 3300);
DISPLAY 0.510638 (-2650 3300);
FORCEPROP 1 LAST PACK_TYPE 0402
J 0
(-2650 3200);
DISPLAY 0.510638 (-2650 3200);
FORCEPROP 1 LAST $LOCATION C2344
J 0
(-2650 3500);
DISPLAY 0.978723 (-2650 3500);
FORCEPROP 1 LASTPIN (-2700 3500) $PN 1
J 0
(-2690 3480);
DISPLAY 0.787234 (-2690 3480);
PAINT MONO (-2690 3480);
FORCEPROP 1 LASTPIN (-2700 3300) $PN 2
J 0
(-2690 3280);
DISPLAY 0.787234 (-2690 3280);
PAINT MONO (-2690 3280);
FORCEPROP 2 LAST CDS_LIB pure_quanta
J 0
(-2700 3400);
DISPLAY INVISIBLE (-2700 3400);
FORCEPROP 1 LAST PATH I87
J 0
(-2650 3550);
DISPLAY 0.978723 (-2650 3550);
PAINT WHITE (-2650 3550);
DISPLAY INVISIBLE (-2650 3550);
FORCEPROP 0 LAST CDS_LOCATION C2344
J 0
(-2650 3550);
DISPLAY 1.021277 (-2650 3550);
DISPLAY INVISIBLE (-2650 3550);
FORCEPROP 0 LAST $SEC 1
J 0
(-2650 3550);
DISPLAY 0.680851 (-2650 3550);
PAINT MONO (-2650 3550);
DISPLAY INVISIBLE (-2650 3550);
FORCEPROP 0 LAST CDS_SEC 1
J 0
(-2650 3550);
DISPLAY 1.021277 (-2650 3550);
DISPLAY INVISIBLE (-2650 3550);
FORCEADD OFFPAGE..1
R 2
(-2275 3075);
FORCEPROP 2 LAST $XR0 154 
J 0
(-2089 3075);
DISPLAY 0.638298 (-2089 3075);
PAINT MONO (-2089 3075);
FORCEPROP 2 LAST CDS_LIB standard
J 2
(-2275 3075);
DISPLAY INVISIBLE (-2275 3075);
FORCEPROP 1 LAST OFFPAGE TRUE
J 2
(-2600 2950);
DISPLAY 0.872340 (-2600 2950);
PAINT GREEN (-2600 2950);
DISPLAY INVISIBLE (-2600 2950);
FORCEPROP 1 LAST COMMENT_BODY TRUE
J 2
(-2400 2975);
DISPLAY 0.872340 (-2400 2975);
PAINT GREEN (-2400 2975);
DISPLAY INVISIBLE (-2400 2975);
FORCEPROP 2 LAST PATH I88
J 2
(-2325 3150);
DISPLAY 1.021277 (-2325 3150);
DISPLAY INVISIBLE (-2325 3150);
FORCEADD OFFPAGE..2
(-4625 7000);
FORCEPROP 2 LAST $XR0 153 
J 0
(-4436 7000);
DISPLAY 0.638298 (-4436 7000);
PAINT MONO (-4436 7000);
FORCEPROP 2 LAST CDS_LIB standard
J 0
(-4625 7000);
PAINT MONO (-4625 7000);
DISPLAY INVISIBLE (-4625 7000);
FORCEPROP 1 LAST OFFPAGE TRUE
J 0
(-4300 6875);
DISPLAY 0.872340 (-4300 6875);
PAINT GREEN (-4300 6875);
DISPLAY INVISIBLE (-4300 6875);
FORCEPROP 1 LAST COMMENT_BODY TRUE
J 0
(-4670 6905);
DISPLAY 0.872340 (-4670 6905);
PAINT GREEN (-4670 6905);
DISPLAY INVISIBLE (-4670 6905);
FORCEPROP 2 LAST PATH I9
J 0
(-4425 7050);
DISPLAY 1.021277 (-4425 7050);
DISPLAY INVISIBLE (-4425 7050);
FORCEADD Q_RES..1
(-4800 3125);
FORCEPROP 1 LAST PART_NUMBER CS00002JB13
J 0
(-4900 3175);
DISPLAY 0.510638 (-4900 3175);
DISPLAY INVISIBLE (-4900 3175);
FORCEPROP 1 LAST VALUE 0
J 2
(-4675 3125);
DISPLAY 0.510638 (-4675 3125);
FORCEPROP 1 LAST MATERIAL CHIP
J 0
(-4575 3125);
DISPLAY 0.510638 (-4575 3125);
FORCEPROP 1 LAST $LOCATION R4601
J 0
(-5000 3125);
DISPLAY 0.638298 (-5000 3125);
FORCEPROP 1 LASTPIN (-4900 3125) $PN 1
J 0
(-4888 3137);
DISPLAY 0.787234 (-4888 3137);
PAINT MONO (-4888 3137);
FORCEPROP 1 LASTPIN (-4700 3125) $PN 2
J 0
(-4738 3137);
DISPLAY 0.787234 (-4738 3137);
PAINT MONO (-4738 3137);
FORCEPROP 2 LAST CDS_LIB pure_quanta
J 0
(-4800 3125);
DISPLAY INVISIBLE (-4800 3125);
FORCEPROP 1 LAST PACK_TYPE 0402LF
J 0
(-4900 3225);
DISPLAY 0.510638 (-4900 3225);
DISPLAY INVISIBLE (-4900 3225);
FORCEPROP 1 LAST TOLERANCE 5%
J 0
(-4650 3125);
DISPLAY 0.510638 (-4650 3125);
DISPLAY INVISIBLE (-4650 3125);
FORCEPROP 1 LAST WATTAGE 1/16W
J 2
(-4550 3225);
DISPLAY 0.510638 (-4550 3225);
DISPLAY INVISIBLE (-4550 3225);
FORCEPROP 1 LAST PATH I90
J 0
(-4850 3275);
DISPLAY 0.978723 (-4850 3275);
PAINT WHITE (-4850 3275);
DISPLAY INVISIBLE (-4850 3275);
FORCEPROP 0 LAST CDS_LOCATION R4601
J 0
(-5000 3175);
DISPLAY 1.021277 (-5000 3175);
DISPLAY INVISIBLE (-5000 3175);
FORCEPROP 0 LAST $SEC 1
J 0
(-5000 3175);
DISPLAY 0.680851 (-5000 3175);
PAINT MONO (-5000 3175);
DISPLAY INVISIBLE (-5000 3175);
FORCEPROP 0 LAST CDS_SEC 1
J 0
(-5000 3175);
DISPLAY 1.021277 (-5000 3175);
DISPLAY INVISIBLE (-5000 3175);
FORCEADD OFFPAGE..2
R 2
(-5875 3125);
FORCEPROP 2 LAST $XR0 153 
J 0
(-6130 3125);
DISPLAY 0.638298 (-6130 3125);
PAINT MONO (-6130 3125);
FORCEPROP 2 LAST CDS_LIB standard
J 2
(-5875 3125);
DISPLAY INVISIBLE (-5875 3125);
FORCEPROP 1 LAST OFFPAGE TRUE
J 2
(-6200 3000);
DISPLAY 0.872340 (-6200 3000);
PAINT GREEN (-6200 3000);
DISPLAY INVISIBLE (-6200 3000);
FORCEPROP 1 LAST COMMENT_BODY TRUE
J 2
(-5830 3030);
DISPLAY 0.872340 (-5830 3030);
PAINT GREEN (-5830 3030);
DISPLAY INVISIBLE (-5830 3030);
FORCEPROP 2 LAST PATH I91
J 0
(-6125 3175);
DISPLAY 1.021277 (-6125 3175);
DISPLAY INVISIBLE (-6125 3175);
FORCEADD 74LVC1G66GV..1
(-3350 3125);
FORCEPROP 1 LAST PART_NUMBER AL001G66000
J 0
(-3505 3369);
DISPLAY 0.723404 (-3505 3369);
PAINT GREEN (-3505 3369);
DISPLAY INVISIBLE (-3505 3369);
FORCEPROP 2 LAST VALUE 74LVC1G66GV
J 0
(-3500 3500);
DISPLAY 1.021277 (-3500 3500);
FORCEPROP 2 LAST PART_TYPE SMLF
J 0
(-3500 3550);
DISPLAY 1.021277 (-3500 3550);
FORCEPROP 1 LAST MATERIAL IC
J 0
(-3505 3280);
DISPLAY 0.723404 (-3505 3280);
PAINT GREEN (-3505 3280);
FORCEPROP 1 LAST LOCATION U320
J 0
(-3500 3450);
DISPLAY 0.723404 (-3500 3450);
PAINT GREEN (-3500 3450);
FORCEPROP 0 LASTPIN (-3050 3075) $PN 4
J 0
(-3040 3085);
DISPLAY 0.680851 (-3040 3085);
PAINT MONO (-3040 3085);
FORCEPROP 0 LASTPIN (-3650 3025) $PN 3
J 2
(-3660 3035);
DISPLAY 0.680851 (-3660 3035);
PAINT MONO (-3660 3035);
FORCEPROP 0 LASTPIN (-3050 3225) $PN 5
J 0
(-3040 3235);
DISPLAY 0.680851 (-3040 3235);
PAINT MONO (-3040 3235);
FORCEPROP 0 LASTPIN (-3650 3225) $PN 1
J 2
(-3660 3235);
DISPLAY 0.680851 (-3660 3235);
PAINT MONO (-3660 3235);
FORCEPROP 0 LASTPIN (-3650 3125) $PN 2
J 2
(-3660 3135);
DISPLAY 0.680851 (-3660 3135);
PAINT MONO (-3660 3135);
FORCEPROP 1 LAST CDS_LMAN_SYM_OUTLINE -150,150,150,-150
J 0
(-3350 3125);
DISPLAY 0.468085 (-3350 3125);
PAINT GREEN (-3350 3125);
DISPLAY INVISIBLE (-3350 3125);
FORCEPROP 2 LAST CDS_LIB pure_quanta
J 2
(-3350 3125);
DISPLAY INVISIBLE (-3350 3125);
FORCEPROP 1 LAST PATH I92
J 0
(-3200 2975);
DISPLAY 0.723404 (-3200 2975);
PAINT GREEN (-3200 2975);
DISPLAY INVISIBLE (-3200 2975);
FORCEPROP 1 LAST PIN_NAMES_ROTATE True
J 0
(-3350 3125);
DISPLAY 0.489362 (-3350 3125);
PAINT GREEN (-3350 3125);
DISPLAY INVISIBLE (-3350 3125);
FORCEPROP 0 LAST $SEC 1
J 0
(-3500 3600);
DISPLAY 0.680851 (-3500 3600);
PAINT MONO (-3500 3600);
DISPLAY INVISIBLE (-3500 3600);
FORCEPROP 0 LAST CDS_SEC 1
J 0
(-3500 3600);
DISPLAY 1.021277 (-3500 3600);
DISPLAY INVISIBLE (-3500 3600);
FORCEADD DNS..2
(-3950 4425);
PAINT RED (-3950 4425);
FORCEPROP 2 LAST CDS_LIB mstr_misc
J 0
(-3950 4425);
DISPLAY INVISIBLE (-3950 4425);
FORCEPROP 1 LAST COMMENT_BODY TRUE
R 1
J 0
(-3875 4200);
DISPLAY 0.872340 (-3875 4200);
PAINT GREEN (-3875 4200);
DISPLAY INVISIBLE (-3875 4200);
FORCEADD CAD_NOTE..1
(-3300 4675);
FORCEPROP 0 LAST S1 PLACE R2487 CLOSE TO U157
J 0
(-3450 4525);
DISPLAY 0.808511 (-3450 4525);
PAINT SKYBLUE (-3450 4525);
FORCEPROP 2 LAST CDS_LIB logical_power
J 0
(-3300 4675);
DISPLAY INVISIBLE (-3300 4675);
FORCEPROP 1 LAST COMMENT_BODY TRUE
J 0
(-3275 4775);
DISPLAY 0.978723 (-3275 4775);
DISPLAY INVISIBLE (-3275 4775);
FORCEADD QUANTA_TITLE_BLOCK_C..1
(-1575 1525);
FORCEPROP 0 LAST CDS_CON_LAST_MODIFIED Fri Aug 25 14:02:18 2023
J 0
(-3460 1540);
PAINT MONO (-3460 1540);
DISPLAY INVISIBLE (-3460 1540);
FORCEPROP 1 LAST CUSTOM_TXT_CDS <CON_LAST_MODIFIED>
J 0
(-3460 1540);
DISPLAY 0.978723 (-3460 1540);
FORCEPROP 2 LAST CUSTOM_TXT_CDS <XR_PAGE_TITLE>
J 0
(-9465 6775);
DISPLAY 0.638298 (-9465 6775);
PAINT PINK (-9465 6775);
DISPLAY INVISIBLE (-9465 6775);
FORCEPROP 2 LAST CUSTOM_TXT_CDS <Q_NUMBER>
J 0
(-2978 1628);
DISPLAY 1.212766 (-2978 1628);
FORCEPROP 2 LAST CUSTOM_TXT_CDS <CON_PAGE_NUM> OF <CON_TOTAL_PAGES>
J 0
(-2046 1543);
DISPLAY 0.978723 (-2046 1543);
FORCEPROP 1 LAST CUSTOM_TXT_CDS <NAME_2>
J 0
(-4750 1575);
FORCEPROP 1 LAST CUSTOM_TXT_CDS <NAME_1>
J 0
(-4750 1700);
FORCEPROP 1 LAST CUSTOM_TXT_CDS <Q_PROJ>
J 0
(-3957 1627);
DISPLAY 1.212766 (-3957 1627);
FORCEPROP 1 LAST CUSTOM_TXT_CDS <Q_REV>
J 0
(-1759 1628);
DISPLAY 1.212766 (-1759 1628);
FORCEPROP 1 LAST Q_TITLE PCIE - SFF OCP3.0 (3/3)
J 0
(-10941 1551);
DISPLAY 1.957447 (-10941 1551);
PAINT GREEN (-10941 1551);
FORCEPROP 1 LAST Q_DEPT 
J 1
(-5338 1574);
DISPLAY 1.957447 (-5338 1574);
PAINT GREEN (-5338 1574);
FORCEPROP 2 LAST CDS_XR_PAGE_TITLE CR-155 : @S9S_MB_2U_LIB.S9S_MB_2U(SCH_1):PAGE155
J 0
(-9465 6775);
DISPLAY 0.638298 (-9465 6775);
PAINT PINK (-9465 6775);
DISPLAY INVISIBLE (-9465 6775);
FORCEPROP 1 LAST COMMENT_BODY TRUE
J 0
(-1563 1512);
DISPLAY 0.978723 (-1563 1512);
PAINT GREEN (-1563 1512);
DISPLAY INVISIBLE (-1563 1512);
FORCEPROP 2 LAST PAGE_BORDER TRUE
J 0
(-9465 6775);
DISPLAY 0.638298 (-9465 6775);
PAINT PINK (-9465 6775);
DISPLAY INVISIBLE (-9465 6775);
FORCEPROP 1 LAST CDS_LMAN_SYM_OUTLINE -9475,6775,100,-125
J 0
(-1575 1525);
DISPLAY 0.468085 (-1575 1525);
PAINT GREEN (-1575 1525);
DISPLAY INVISIBLE (-1575 1525);
FORCEPROP 2 LAST CDS_LIB pure_quanta
J 0
(-1575 1525);
PAINT MONO (-1575 1525);
DISPLAY INVISIBLE (-1575 1525);
WIRE 16 -1 (-6950 6275)(-6950 6225);
WIRE 16 -1 (-6050 6050)(-6050 6100);
WIRE 16 -1 (-7225 4650)(-7225 4700);
WIRE 16 -1 (-2900 3625)(-2900 3575);
WIRE 16 -1 (-4700 4600)(-4700 4550);
WIRE 16 -1 (-6650 2900)(-6650 2975);
WIRE 16 -1 (-6425 2900)(-6650 2900);
WIRE 16 -1 (-6650 2475)(-6650 2900);
WIRE 16 -1 (-9950 2825)(-9950 2925);
WIRE 16 -1 (-9950 2375)(-9950 2825);
WIRE 16 -1 (-9950 2825)(-10050 2825);
WIRE 16 -1 (-8075 4850)(-8075 4950);
WIRE 16 -1 (-8350 4850)(-8075 4850);
WIRE 16 -1 (-8075 4750)(-8075 4850);
WIRE 16 -1 (-9575 4700)(-9575 4775);
WIRE 16 -1 (-9850 4700)(-9575 4700);
WIRE 16 -1 (-9575 4575)(-9575 4700);
WIRE 16 -1 (-3950 4550)(-3950 4600);
WIRE 16 -1 (-8000 7725)(-8000 7775);
WIRE 16 -1 (-8200 7725)(-8000 7725);
WIRE 16 -1 (-8000 7325)(-8000 7725);
WIRE 16 -1 (-3775 3025)(-3775 2925);
WIRE 16 -1 (-3650 3025)(-3775 3025);
WIRE 16 -1 (-2700 3300)(-2700 3225);
WIRE 16 -1 (-4500 4275)(-4500 4200);
WIRE 16 -1 (-5600 4000)(-5600 3825);
WIRE 16 -1 (-5400 4000)(-5600 4000);
WIRE 16 -1 (-6425 2600)(-6425 2525);
WIRE 16 -1 (-6725 2050)(-6725 2125);
WIRE 16 -1 (-9000 2150)(-9000 2225);
WIRE 16 -1 (-10050 2425)(-10050 2500);
WIRE 16 -1 (-8350 3850)(-8350 3700);
WIRE 16 -1 (-8075 4550)(-8075 4475);
WIRE 16 -1 (-7875 7125)(-7875 7025);
WIRE 16 -1 (-6750 5950)(-6750 5875);
WIRE 16 -1 (-7900 5575)(-7900 5400);
WIRE 16 -1 (-7700 5575)(-7900 5575);
WIRE 16 -1 (-8200 7450)(-8200 7375);
WIRE 16 2175 (-6225 6275)(-5575 6275);
WIRE 16 2175 (-5575 6275)(-5575 5725);
WIRE 16 2175 (-6225 6275)(-6225 5725);
WIRE 16 2175 (-6225 5725)(-5575 5725);
WIRE 16 -1 (-6050 5575)(-7150 5575);
FORCEPROP 0 LAST CDS_PHYS_NET_NAME OCP_SFF_PWRBRK_R_N
J 0
(-6635 5617);
PAINT MONO (-6635 5617);
DISPLAY INVISIBLE (-6635 5617);
FORCEPROP 2 LAST SIG_NAME OCP_SFF_PWRBRK_BUFF_N
J 0
(-6885 5585);
DISPLAY 0.680851 (-6885 5585);
PAINT WHITE (-6885 5585);
WIRE 16 -1 (-6050 5850)(-6050 5575);
WIRE 16 -1 (-5600 5575)(-6050 5575);
WIRE 16 -1 (-6150 6775)(-4675 6775);
FORCEPROP 0 LAST CDS_PHYS_NET_NAME RST_PLTRST_B_N
J 0
(-6125 6817);
PAINT MONO (-6125 6817);
DISPLAY INVISIBLE (-6125 6817);
FORCEPROP 0 LAST SIG_NAME RST_PERST2_OCP_SFF_N
J 0
(-5575 6785);
DISPLAY 0.702128 (-5575 6785);
PAINT WHITE (-5575 6785);
WIRE 16 -1 (-6150 6550)(-4675 6550);
FORCEPROP 0 LAST CDS_PHYS_NET_NAME RST_PLTRST_B_N
J 0
(-6125 6592);
PAINT MONO (-6125 6592);
DISPLAY INVISIBLE (-6125 6592);
FORCEPROP 0 LAST SIG_NAME RST_PERST3_OCP_SFF_N
J 0
(-5575 6560);
DISPLAY 0.702128 (-5575 6560);
PAINT WHITE (-5575 6560);
WIRE 16 -1 (-6625 6550)(-6350 6550);
WIRE 16 -1 (-6625 6775)(-6625 6550);
WIRE 16 -1 (-6625 6775)(-6350 6775);
WIRE 16 -1 (-6625 7000)(-6625 6775);
WIRE 16 -1 (-6625 7000)(-6350 7000);
WIRE 16 -1 (-6625 7225)(-6625 7000);
WIRE 16 -1 (-6625 7225)(-6350 7225);
WIRE 16 -1 (-7525 7225)(-6625 7225);
FORCEPROP 0 LAST CDS_PHYS_NET_NAME RST_PLTRST_B_N
J 0
(-7525 7267);
PAINT MONO (-7525 7267);
DISPLAY INVISIBLE (-7525 7267);
FORCEPROP 0 LAST SIG_NAME RST_OCP_V3_1_BUF_N
J 0
(-7375 7235);
DISPLAY 0.702128 (-7375 7235);
PAINT WHITE (-7375 7235);
WIRE 16 -1 (-6750 6225)(-6750 6150);
WIRE 16 -1 (-6950 6225)(-6750 6225);
WIRE 16 -1 (-6950 6225)(-6950 5775);
WIRE 16 -1 (-7150 5775)(-6950 5775);
WIRE 16 -1 (-5400 4200)(-6075 4200);
FORCEPROP 0 LAST CDS_PHYS_NET_NAME RST_PLTRST_B_N
J 0
(-6050 4242);
PAINT MONO (-6050 4242);
DISPLAY INVISIBLE (-6050 4242);
FORCEPROP 0 LAST SIG_NAME NC_U157_NC1
J 0
(-5960 4210);
DISPLAY 0.702128 (-5960 4210);
PAINT WHITE (-5960 4210);
WIRE 16 -1 (-3650 3225)(-4700 3225);
FORCEPROP 0 LAST CDS_PHYS_NET_NAME TP_CLK_50M_NCSI_OCP_LFF_4CP
J 0
(-4335 3259);
PAINT MONO (-4335 3259);
DISPLAY INVISIBLE (-4335 3259);
FORCEPROP 2 LAST SIG_NAME CLK_50M_NCSI_OCP_SFF
J 0
(-4460 3235);
DISPLAY 0.510638 (-4460 3235);
PAINT WHITE (-4460 3235);
WIRE 16 -1 (-3650 3125)(-4700 3125);
FORCEPROP 0 LAST CDS_PHYS_NET_NAME TP_CLK_50M_NCSI_OCP_LFF_4CP
J 0
(-4335 3159);
PAINT MONO (-4335 3159);
DISPLAY INVISIBLE (-4335 3159);
FORCEPROP 2 LAST SIG_NAME CLK_50M_NCSI_OCP_SFF_ISO_R
J 0
(-4460 3135);
DISPLAY 0.510638 (-4460 3135);
PAINT WHITE (-4460 3135);
WIRE 16 -1 (-2325 3075)(-3050 3075);
FORCEPROP 2 LAST SIG_NAME FB_BMC_ISOLATE
J 0
(-2860 3085);
DISPLAY 0.553191 (-2860 3085);
PAINT WHITE (-2860 3085);
WIRE 16 -1 (-2700 3575)(-2700 3500);
WIRE 16 -1 (-2900 3575)(-2700 3575);
WIRE 16 -1 (-2900 3575)(-2900 3225);
WIRE 16 -1 (-3050 3225)(-2900 3225);
WIRE 16 2175 (-5025 3050)(-4475 3050);
WIRE 16 2175 (-4475 3175)(-4475 3050);
WIRE 16 2175 (-5025 3175)(-5025 3050);
WIRE 16 2175 (-5025 3175)(-4475 3175);
WIRE 16 -1 (-4900 3125)(-5825 3125);
FORCEPROP 0 LAST CDS_PHYS_NET_NAME TP_CLK_50M_NCSI_OCP_LFF_4CP
J 0
(-5460 3159);
PAINT MONO (-5460 3159);
DISPLAY INVISIBLE (-5460 3159);
FORCEPROP 2 LAST SIG_NAME CLK_50M_NCSI_OCP_SFF_ISO
J 0
(-5710 3135);
DISPLAY 0.510638 (-5710 3135);
PAINT WHITE (-5710 3135);
WIRE 16 -1 (-7700 5675)(-8825 5675);
FORCEPROP 0 LAST CDS_PHYS_NET_NAME RST_PLTRST_B_N
J 0
(-8800 5717);
PAINT MONO (-8800 5717);
DISPLAY INVISIBLE (-8800 5717);
FORCEPROP 0 LAST SIG_NAME FM_SYS_THROTTLE_R_N
J 0
(-8600 5685);
DISPLAY 0.702128 (-8600 5685);
PAINT WHITE (-8600 5685);
WIRE 16 -1 (-7700 5775)(-8825 5775);
FORCEPROP 0 LAST CDS_PHYS_NET_NAME RST_PLTRST_B_N
J 0
(-8800 5817);
PAINT MONO (-8800 5817);
DISPLAY INVISIBLE (-8800 5817);
FORCEPROP 0 LAST SIG_NAME NC_U104_NC1
J 0
(-8610 5785);
DISPLAY 0.702128 (-8610 5785);
PAINT WHITE (-8610 5785);
WIRE 16 -1 (-4300 5575)(-5400 5575);
FORCEPROP 0 LAST CDS_PHYS_NET_NAME OCP_SFF_PWRBRK_N
J 0
(-4860 5617);
PAINT MONO (-4860 5617);
DISPLAY INVISIBLE (-4860 5617);
FORCEPROP 2 LAST SIG_NAME OCP_SFF_PWRBRK_N
J 0
(-4910 5585);
DISPLAY 0.680851 (-4910 5585);
PAINT WHITE (-4910 5585);
WIRE 16 -1 (-5400 4100)(-6800 4100);
FORCEPROP 0 LAST CDS_PHYS_NET_NAME FB_BMC_RBT_ISOLATE_N
J 0
(-6135 4142);
PAINT MONO (-6135 4142);
DISPLAY INVISIBLE (-6135 4142);
FORCEPROP 2 LAST SIG_NAME OCP_SFF_WAKE_BUFF_R_N
J 0
(-6310 4110);
DISPLAY 0.680851 (-6310 4110);
PAINT WHITE (-6310 4110);
WIRE 16 -1 (-9850 4575)(-9850 4700);
WIRE 16 -1 (-8350 4350)(-8350 4850);
FORCEPROP 0 LAST VOLTAGE 3.3
J 0
(-8250 4350);
PAINT MONO (-8250 4350);
DISPLAY INVISIBLE (-8250 4350);
FORCEPROP 0 LAST CDS_PHYS_NET_NAME P3V3_AUX
J 0
(-8250 4397);
PAINT MONO (-8250 4397);
DISPLAY INVISIBLE (-8250 4397);
FORCEPROP 0 LAST $PHYS_NET_NAME P3V3_AUX
J 0
(-8250 4444);
PAINT MONO (-8250 4444);
DISPLAY INVISIBLE (-8250 4444);
WIRE 16 -1 (-10325 4150)(-9850 4150);
FORCEPROP 0 LAST CDS_PHYS_NET_NAME FB_BMC_RBT_ISOLATE_N
J 0
(-9860 4192);
PAINT MONO (-9860 4192);
DISPLAY INVISIBLE (-9860 4192);
WIRE 16 -1 (-9850 4150)(-8600 4150);
FORCEPROP 2 LAST SIG_NAME IRQ_LVC3_OCP_SFF_WAKE_N
J 0
(-9460 4160);
DISPLAY 0.680851 (-9460 4160);
PAINT WHITE (-9460 4160);
WIRE 16 -1 (-9850 4375)(-9850 4150);
WIRE 16 -1 (-6150 7000)(-4675 7000);
FORCEPROP 0 LAST CDS_PHYS_NET_NAME RST_PLTRST_B_N
J 0
(-6125 7042);
PAINT MONO (-6125 7042);
DISPLAY INVISIBLE (-6125 7042);
FORCEPROP 0 LAST SIG_NAME RST_PERST1_OCP_SFF_N
J 0
(-5575 7010);
DISPLAY 0.702128 (-5575 7010);
PAINT WHITE (-5575 7010);
WIRE 16 -1 (-6150 7225)(-4675 7225);
FORCEPROP 0 LAST CDS_PHYS_NET_NAME RST_PLTRST_B_N
J 0
(-6125 7267);
PAINT MONO (-6125 7267);
DISPLAY INVISIBLE (-6125 7267);
FORCEPROP 0 LAST SIG_NAME RST_PERST0_OCP_SFF_N
J 0
(-5575 7235);
DISPLAY 0.702128 (-5575 7235);
PAINT WHITE (-5575 7235);
WIRE 16 -1 (-7875 7325)(-8000 7325);
WIRE 16 -1 (-8200 7725)(-8200 7650);
WIRE 16 -1 (-8800 7225)(-7875 7225);
FORCEPROP 0 LAST CDS_PHYS_NET_NAME FB_BMC_RBT_ISOLATE_N
J 0
(-8435 7267);
PAINT MONO (-8435 7267);
DISPLAY INVISIBLE (-8435 7267);
FORCEPROP 2 LAST SIG_NAME RST_HP_OCP_V3_1_N
J 0
(-8660 7235);
DISPLAY 0.680851 (-8660 7235);
PAINT WHITE (-8660 7235);
WIRE 16 -1 (-8100 4100)(-7225 4100);
FORCEPROP 0 LAST CDS_PHYS_NET_NAME FB_BMC_RBT_ISOLATE_N
J 0
(-7735 4142);
PAINT MONO (-7735 4142);
DISPLAY INVISIBLE (-7735 4142);
FORCEPROP 2 LAST SIG_NAME OCP_SFF_WAKE_BUFF_N
J 0
(-7960 4110);
DISPLAY 0.680851 (-7960 4110);
PAINT WHITE (-7960 4110);
WIRE 16 -1 (-7000 4100)(-7225 4100);
WIRE 16 -1 (-7225 4450)(-7225 4100);
WIRE 16 -1 (-10400 2675)(-10400 2825);
WIRE 16 -1 (-10400 2825)(-10050 2825);
WIRE 16 -1 (-10050 2700)(-10050 2825);
WIRE 16 -1 (-9775 2375)(-9950 2375);
WIRE 16 -1 (-6850 2125)(-6725 2125);
WIRE 16 -1 (-9125 2375)(-8425 2375);
FORCEPROP 2 LAST SIG_NAME CLK_50M_RMII
J 0
(-9010 2385);
DISPLAY 0.553191 (-9010 2385);
PAINT WHITE (-9010 2385);
WIRE 16 -1 (-5825 2325)(-6850 2325);
FORCEPROP 0 LAST CDS_PHYS_NET_NAME TP_CLK_50M_NCSI_OCP_LFF_4CP
J 0
(-6485 2359);
PAINT MONO (-6485 2359);
DISPLAY INVISIBLE (-6485 2359);
FORCEPROP 2 LAST SIG_NAME CLK_50M_NCSI_OCP_1
J 0
(-6560 2335);
DISPLAY 0.510638 (-6560 2335);
PAINT WHITE (-6560 2335);
WIRE 16 -1 (-9575 4050)(-8600 4050);
FORCEPROP 0 LAST CDS_PHYS_NET_NAME FB_BMC_RBT_ISOLATE_N
J 0
(-9335 4092);
PAINT MONO (-9335 4092);
DISPLAY INVISIBLE (-9335 4092);
FORCEPROP 2 LAST SIG_NAME PU_OCP_SFF_WAKE_OE
J 0
(-9460 4060);
DISPLAY 0.680851 (-9460 4060);
PAINT WHITE (-9460 4060);
WIRE 16 -1 (-9575 4375)(-9575 4050);
WIRE 16 -1 (-4850 4200)(-4700 4200);
WIRE 16 -1 (-4700 4550)(-4700 4200);
WIRE 16 -1 (-4700 4550)(-4500 4550);
WIRE 16 -1 (-4500 4550)(-4500 4475);
WIRE 16 -1 (-5825 2375)(-6850 2375);
FORCEPROP 0 LAST CDS_PHYS_NET_NAME TP_CLK_50M_NCSI_OCP_LFF_4CP
J 0
(-6485 2409);
PAINT MONO (-6485 2409);
DISPLAY INVISIBLE (-6485 2409);
FORCEPROP 2 LAST SIG_NAME CLK_50M_BMC_MAC_R
J 0
(-6560 2385);
DISPLAY 0.510638 (-6560 2385);
PAINT WHITE (-6560 2385);
WIRE 16 -1 (-5825 2275)(-6850 2275);
FORCEPROP 0 LAST CDS_PHYS_NET_NAME TP_CLK_50M_NCSI_OCP_LFF_4CP
J 0
(-6485 2309);
PAINT MONO (-6485 2309);
DISPLAY INVISIBLE (-6485 2309);
FORCEPROP 2 LAST SIG_NAME CLK_50M_NCSI_OCP_2
J 0
(-6560 2285);
DISPLAY 0.510638 (-6560 2285);
PAINT WHITE (-6560 2285);
WIRE 16 -1 (-5825 2225)(-6850 2225);
FORCEPROP 0 LAST CDS_PHYS_NET_NAME TP_CLK_50M_NCSI_OCP_LFF_4CP
J 0
(-6485 2259);
PAINT MONO (-6485 2259);
DISPLAY INVISIBLE (-6485 2259);
FORCEPROP 2 LAST SIG_NAME TP_CLK_50M_PCH_LOM
J 0
(-6560 2235);
DISPLAY 0.510638 (-6560 2235);
PAINT WHITE (-6560 2235);
WIRE 16 -1 (-3950 4000)(-3750 4000);
WIRE 16 -1 (-3950 4350)(-3950 4000);
WIRE 16 -1 (-4850 4000)(-3950 4000);
FORCEPROP 0 LAST CDS_PHYS_NET_NAME IRQ_LVC3_WAKE_N
J 0
(-4825 4042);
PAINT MONO (-4825 4042);
DISPLAY INVISIBLE (-4825 4042);
FORCEPROP 0 LAST SIG_NAME IRQ_LVC3_WAKE_BUF_N
J 0
(-4685 4010);
DISPLAY 0.702128 (-4685 4010);
PAINT WHITE (-4685 4010);
WIRE 16 -1 (-8175 2225)(-7450 2225);
WIRE 16 -1 (-8175 2000)(-8175 2225);
WIRE 16 -1 (-10400 2000)(-8175 2000);
WIRE 16 -1 (-10400 2225)(-10400 2000);
WIRE 16 -1 (-9775 2225)(-10400 2225);
FORCEPROP 2 LAST SIG_NAME CLK_50M_EN
J 0
(-10185 2235);
DISPLAY 0.638298 (-10185 2235);
PAINT WHITE (-10185 2235);
WIRE 16 -1 (-10400 2475)(-10400 2225);
WIRE 16 -1 (-7450 2375)(-8225 2375);
FORCEPROP 2 LAST SIG_NAME CLK_50M_RMII_R
J 0
(-7985 2385);
DISPLAY 0.553191 (-7985 2385);
PAINT WHITE (-7985 2385);
WIRE 16 -1 (-9125 2225)(-9000 2225);
WIRE 16 -1 (-6850 2475)(-6650 2475);
WIRE 16 -1 (-6425 2800)(-6425 2900);
WIRE 16 -1 (-3550 4000)(-2500 4000);
FORCEPROP 0 LAST CDS_PHYS_NET_NAME IRQ_LVC3_WAKE_N
J 0
(-3525 4042);
PAINT MONO (-3525 4042);
DISPLAY INVISIBLE (-3525 4042);
FORCEPROP 0 LAST SIG_NAME IRQ_LVC3_WAKE_N
J 0
(-3060 4010);
DISPLAY 0.702128 (-3060 4010);
PAINT WHITE (-3060 4010);
WIRE 16 -1 (-4575 2375)(-5625 2375);
FORCEPROP 0 LAST CDS_PHYS_NET_NAME TP_CLK_50M_NCSI_OCP_LFF_4CP
J 0
(-5260 2409);
PAINT MONO (-5260 2409);
DISPLAY INVISIBLE (-5260 2409);
FORCEPROP 2 LAST SIG_NAME CLK_50M_RMII_BMC_OCP
J 0
(-5135 2385);
DISPLAY 0.510638 (-5135 2385);
PAINT WHITE (-5135 2385);
WIRE 16 -1 (-4575 2275)(-5625 2275);
FORCEPROP 0 LAST CDS_PHYS_NET_NAME TP_CLK_50M_NCSI_OCP_LFF_4CP
J 0
(-5260 2309);
PAINT MONO (-5260 2309);
DISPLAY INVISIBLE (-5260 2309);
FORCEPROP 2 LAST SIG_NAME CLK_50M_NCSI_OCP_V3_2
J 0
(-5135 2285);
DISPLAY 0.510638 (-5135 2285);
PAINT WHITE (-5135 2285);
WIRE 16 -1 (-4575 2325)(-5625 2325);
FORCEPROP 0 LAST CDS_PHYS_NET_NAME TP_CLK_50M_NCSI_OCP_LFF_4CP
J 0
(-5260 2359);
PAINT MONO (-5260 2359);
DISPLAY INVISIBLE (-5260 2359);
FORCEPROP 2 LAST SIG_NAME CLK_50M_NCSI_OCP_SFF
J 0
(-5135 2335);
DISPLAY 0.510638 (-5135 2335);
PAINT WHITE (-5135 2335);
DOT 1 (-8000 7725);
DOT 1 (-6050 5575);
DOT 1 (-6950 6225);
DOT 1 (-6625 6775);
DOT 1 (-6625 7000);
DOT 1 (-6625 7225);
DOT 1 (-3950 4000);
DOT 1 (-7225 4100);
DOT 1 (-9850 4150);
DOT 1 (-9575 4700);
DOT 1 (-8075 4850);
DOT 1 (-10400 2225);
DOT 1 (-10050 2825);
DOT 1 (-9950 2825);
DOT 1 (-6650 2900);
DOT 1 (-4700 4550);
DOT 1 (-2900 3575);
FORCENOTE
20210607 MODIFY FOR GT
(-7650 7775) 0;
DISPLAY LEFT (-7650 7775);
DISPLAY 2.510638 (-7650 7775);
PAINT PINK (-7650 7775);
FORCENOTE
20210706 MODIFY FOR GT
(-10675 3275) 0;
DISPLAY LEFT (-10675 3275);
DISPLAY 2.510638 (-10675 3275);
PAINT PINK (-10675 3275);
FORCENOTE
20220120 ADD R4601
(-5325 2950) 0;
DISPLAY LEFT (-5325 2950);
DISPLAY 1.276596 (-5325 2950);
PAINT PINK (-5325 2950);
QUIT
